FILE_TYPE = MACRO_DRAWING;
SET COLOR_WIRE YELLOW;
SET COLOR_PROP ORANGE;
SET COLOR_DOT WHITE;
SET COLOR_ARC YELLOW;
SET COLOR_BODY GREEN;
SET COLOR_NOTE PURPLE;
SET PROP_DISPLAY VALUE;
SET PAGE_NUMBER P443;
FORCEADD Q_RES..2
R 2
(-4325 2575);
FORCEPROP 1 LAST LOCATION R705
J 2
(-4370 2700);
DISPLAY 0.978723 (-4370 2700);
FORCEPROP 0 LAST $SEC 1
J 0
(-4350 2750);
DISPLAY 0.680851 (-4350 2750);
PAINT MONO (-4350 2750);
DISPLAY INVISIBLE (-4350 2750);
FORCEPROP 0 LAST CDS_SEC 1
J 0
(-4350 2750);
DISPLAY 0.680851 (-4350 2750);
DISPLAY INVISIBLE (-4350 2750);
FORCEPROP 1 LASTPIN (-4325 2675) $PN 1
J 2
(-4330 2637);
DISPLAY 0.787234 (-4330 2637);
PAINT MONO (-4330 2637);
FORCEPROP 1 LASTPIN (-4325 2475) $PN 2
J 2
(-4330 2485);
DISPLAY 0.787234 (-4330 2485);
PAINT MONO (-4330 2485);
FORCEPROP 1 LAST WATTAGE 1/4W
J 2
(-4365 2550);
DISPLAY 0.978723 (-4365 2550);
FORCEPROP 1 LAST MATERIAL EMPTY
J 2
(-4365 2500);
DISPLAY 0.978723 (-4365 2500);
FORCEPROP 1 LAST PACK_TYPE 0603LF
J 2
(-4365 2400);
DISPLAY 0.978723 (-4365 2400);
FORCEPROP 1 LAST VALUE 0
J 2
(-4370 2650);
DISPLAY 0.978723 (-4370 2650);
FORCEPROP 1 LAST TOLERANCE 5%
J 2
(-4370 2600);
DISPLAY 0.978723 (-4370 2600);
FORCEPROP 2 LAST CDS_LIB pure_quanta
J 2
(-4325 2575);
DISPLAY INVISIBLE (-4325 2575);
FORCEPROP 1 LAST PATH I10
J 2
(-4375 2750);
DISPLAY 0.978723 (-4375 2750);
PAINT WHITE (-4375 2750);
DISPLAY INVISIBLE (-4375 2750);
FORCEPROP 1 LAST PART_NUMBER CS00006J900
J 2
(-4365 2450);
DISPLAY 0.978723 (-4365 2450);
DISPLAY INVISIBLE (-4365 2450);
FORCEADD Q_RES..1
(-3950 2300);
FORCEPROP 1 LAST LOCATION R712
J 0
(-4000 2350);
DISPLAY 0.978723 (-4000 2350);
FORCEPROP 0 LAST $SEC 1
J 0
(-4000 2400);
DISPLAY 0.680851 (-4000 2400);
PAINT MONO (-4000 2400);
DISPLAY INVISIBLE (-4000 2400);
FORCEPROP 0 LAST CDS_SEC 1
J 0
(-4000 2400);
DISPLAY 0.680851 (-4000 2400);
DISPLAY INVISIBLE (-4000 2400);
FORCEPROP 1 LASTPIN (-4050 2300) $PN 1
J 0
(-4038 2312);
DISPLAY 0.787234 (-4038 2312);
PAINT MONO (-4038 2312);
FORCEPROP 1 LASTPIN (-3850 2300) $PN 2
J 0
(-3888 2312);
DISPLAY 0.787234 (-3888 2312);
PAINT MONO (-3888 2312);
FORCEPROP 1 LAST PACK_TYPE 0603LF
J 0
(-3700 2150);
DISPLAY 0.978723 (-3700 2150);
FORCEPROP 1 LAST TOLERANCE 5%
J 0
(-3950 2200);
DISPLAY 0.978723 (-3950 2200);
FORCEPROP 1 LAST VALUE 0
J 2
(-3975 2200);
DISPLAY 0.978723 (-3975 2200);
FORCEPROP 1 LAST MATERIAL CHIP
J 0
(-3950 2150);
DISPLAY 0.978723 (-3950 2150);
FORCEPROP 1 LAST WATTAGE 1/4W
J 2
(-3975 2150);
DISPLAY 0.978723 (-3975 2150);
FORCEPROP 2 LAST CDS_LIB pure_quanta
J 0
(-3950 2300);
DISPLAY INVISIBLE (-3950 2300);
FORCEPROP 1 LAST PATH I11
J 0
(-4000 2450);
DISPLAY 0.978723 (-4000 2450);
PAINT WHITE (-4000 2450);
DISPLAY INVISIBLE (-4000 2450);
FORCEPROP 1 LAST PART_NUMBER CS00006J900
J 0
(-4175 2075);
DISPLAY 0.978723 (-4175 2075);
DISPLAY INVISIBLE (-4175 2075);
FORCEADD Q_INDUCTOR..1
(-7800 4275);
FORCEPROP 1 LAST LOCATION L5
J 0
(-7925 4435);
DISPLAY 0.723404 (-7925 4435);
PAINT GREEN (-7925 4435);
FORCEPROP 0 LAST $SEC 1
J 0
(-7925 4525);
DISPLAY 0.680851 (-7925 4525);
PAINT MONO (-7925 4525);
DISPLAY INVISIBLE (-7925 4525);
FORCEPROP 0 LAST CDS_SEC 1
J 0
(-7925 4525);
DISPLAY 0.680851 (-7925 4525);
DISPLAY INVISIBLE (-7925 4525);
FORCEPROP 0 LASTPIN (-7900 4250) $PN 1
J 2
(-7910 4260);
DISPLAY 0.680851 (-7910 4260);
PAINT MONO (-7910 4260);
FORCEPROP 0 LASTPIN (-7700 4250) $PN 2
J 0
(-7690 4260);
DISPLAY 0.680851 (-7690 4260);
PAINT MONO (-7690 4260);
FORCEPROP 2 LAST PACK_TYPE SMLF
J 0
(-7925 4475);
DISPLAY 0.680851 (-7925 4475);
FORCEPROP 1 LAST MATERIAL IND
J 0
(-7925 4330);
DISPLAY 0.723404 (-7925 4330);
PAINT GREEN (-7925 4330);
FORCEPROP 2 LAST VALUE BLM21SN300SN1D/5A
J 0
(-8050 4175);
DISPLAY 0.680851 (-8050 4175);
FORCEPROP 2 LAST CDS_LIB pure_quanta
J 0
(-7800 4275);
DISPLAY INVISIBLE (-7800 4275);
FORCEPROP 1 LAST NEEDS_NO_SIZE TRUE
J 0
(-7800 4275);
DISPLAY 0.468085 (-7800 4275);
PAINT GREEN (-7800 4275);
DISPLAY INVISIBLE (-7800 4275);
FORCEPROP 1 LAST PATH I12
J 0
(-7725 4330);
DISPLAY 0.723404 (-7725 4330);
PAINT GREEN (-7725 4330);
DISPLAY INVISIBLE (-7725 4330);
FORCEPROP 1 LAST PART_NUMBER CX300SN1000
J 0
(-7925 4385);
DISPLAY 0.723404 (-7925 4385);
PAINT GREEN (-7925 4385);
DISPLAY INVISIBLE (-7925 4385);
FORCEADD Q_CAP..1
(-7225 4000);
FORCEPROP 1 LAST LOCATION C103
J 0
(-7175 4100);
DISPLAY 0.638298 (-7175 4100);
PAINT WHITE (-7175 4100);
FORCEPROP 0 LAST $SEC 1
J 0
(-7175 4125);
DISPLAY 0.680851 (-7175 4125);
PAINT MONO (-7175 4125);
DISPLAY INVISIBLE (-7175 4125);
FORCEPROP 0 LAST CDS_SEC 1
J 0
(-7175 4125);
DISPLAY 0.680851 (-7175 4125);
DISPLAY INVISIBLE (-7175 4125);
FORCEPROP 1 LASTPIN (-7225 4100) $PN 1
J 0
(-7215 4080);
DISPLAY 0.787234 (-7215 4080);
PAINT MONO (-7215 4080);
FORCEPROP 1 LASTPIN (-7225 3900) $PN 2
J 0
(-7215 3880);
DISPLAY 0.787234 (-7215 3880);
PAINT MONO (-7215 3880);
FORCEPROP 1 LAST VOLTAGE 4V
J 0
(-7175 4000);
DISPLAY 0.510638 (-7175 4000);
FORCEPROP 1 LAST MATERIAL X6S
J 0
(-7175 3900);
DISPLAY 0.510638 (-7175 3900);
FORCEPROP 1 LAST TOLERANCE 20%
J 0
(-7175 3950);
DISPLAY 0.510638 (-7175 3950);
FORCEPROP 1 LAST PACK_TYPE C0805
J 0
(-7175 3850);
DISPLAY 0.510638 (-7175 3850);
FORCEPROP 1 LAST VALUE 100UF
J 0
(-7175 4050);
DISPLAY 0.510638 (-7175 4050);
FORCEPROP 2 LAST CDS_LIB pure_quanta
J 0
(-7225 4000);
DISPLAY INVISIBLE (-7225 4000);
FORCEPROP 1 LAST PATH I13
J 0
(-7175 4150);
DISPLAY 0.978723 (-7175 4150);
PAINT WHITE (-7175 4150);
DISPLAY INVISIBLE (-7175 4150);
FORCEPROP 1 LAST PART_NUMBER CH710KMEA01
J 0
(-7175 3850);
DISPLAY 0.404255 (-7175 3850);
DISPLAY INVISIBLE (-7175 3850);
FORCEADD Q_CAP..1
(-7000 4000);
FORCEPROP 1 LAST LOCATION C111
J 0
(-6950 4100);
DISPLAY 0.638298 (-6950 4100);
PAINT WHITE (-6950 4100);
FORCEPROP 0 LAST $SEC 1
J 0
(-6950 4125);
DISPLAY 0.680851 (-6950 4125);
PAINT MONO (-6950 4125);
DISPLAY INVISIBLE (-6950 4125);
FORCEPROP 0 LAST CDS_SEC 1
J 0
(-6950 4125);
DISPLAY 0.680851 (-6950 4125);
DISPLAY INVISIBLE (-6950 4125);
FORCEPROP 1 LASTPIN (-7000 4100) $PN 1
J 0
(-6990 4080);
DISPLAY 0.787234 (-6990 4080);
PAINT MONO (-6990 4080);
FORCEPROP 1 LASTPIN (-7000 3900) $PN 2
J 0
(-6990 3880);
DISPLAY 0.787234 (-6990 3880);
PAINT MONO (-6990 3880);
FORCEPROP 1 LAST VALUE 22UF
J 0
(-6950 4050);
DISPLAY 0.510638 (-6950 4050);
FORCEPROP 1 LAST VOLTAGE 4V
J 0
(-6950 4000);
DISPLAY 0.510638 (-6950 4000);
FORCEPROP 1 LAST TOLERANCE 20%
J 0
(-6950 3950);
DISPLAY 0.510638 (-6950 3950);
FORCEPROP 1 LAST MATERIAL X6S
J 0
(-6950 3900);
DISPLAY 0.510638 (-6950 3900);
FORCEPROP 1 LAST PACK_TYPE C0402
J 0
(-6950 3850);
DISPLAY 0.510638 (-6950 3850);
FORCEPROP 2 LAST CDS_LIB pure_quanta
J 0
(-7000 4000);
DISPLAY INVISIBLE (-7000 4000);
FORCEPROP 1 LAST PATH I14
J 0
(-6950 4150);
DISPLAY 0.978723 (-6950 4150);
PAINT WHITE (-6950 4150);
DISPLAY INVISIBLE (-6950 4150);
FORCEPROP 1 LAST PART_NUMBER CH622KMEB02
J 0
(-6950 3850);
DISPLAY 0.978723 (-6950 3850);
DISPLAY INVISIBLE (-6950 3850);
FORCEADD P1V0..1
(-7325 4475);
FORCEPROP 3 LASTPIN (-7325 4425) SIG_NAME P1V8_CPU1_RT1_1A\g
J 0
(-7315 4435);
DISPLAY 0.659574 (-7315 4435);
PAINT MONO (-7315 4435);
DISPLAY INVISIBLE (-7315 4435);
FORCEPROP 1 LAST HDL_POWER P1V8_CPU1_RT1_1A
J 1
(-7325 4525);
DISPLAY 0.489362 (-7325 4525);
PAINT SKYBLUE (-7325 4525);
FORCEPROP 2 LAST CDS_LIB pure_quanta_power
J 0
(-7325 4475);
DISPLAY INVISIBLE (-7325 4475);
FORCEPROP 1 LAST PATH I15
J 0
(-7275 4500);
DISPLAY 0.872340 (-7275 4500);
PAINT AQUA (-7275 4500);
DISPLAY INVISIBLE (-7275 4500);
FORCEADD Q_CAP..1
(-7075 4825);
FORCEPROP 1 LAST LOCATION C102
J 0
(-7025 4925);
DISPLAY 0.638298 (-7025 4925);
PAINT WHITE (-7025 4925);
FORCEPROP 0 LAST $SEC 1
J 0
(-7025 4975);
DISPLAY 0.680851 (-7025 4975);
PAINT MONO (-7025 4975);
DISPLAY INVISIBLE (-7025 4975);
FORCEPROP 0 LAST CDS_SEC 1
J 0
(-7025 4975);
DISPLAY 0.680851 (-7025 4975);
DISPLAY INVISIBLE (-7025 4975);
FORCEPROP 1 LASTPIN (-7075 4925) $PN 1
J 0
(-7065 4905);
DISPLAY 0.787234 (-7065 4905);
PAINT MONO (-7065 4905);
FORCEPROP 1 LASTPIN (-7075 4725) $PN 2
J 0
(-7065 4705);
DISPLAY 0.787234 (-7065 4705);
PAINT MONO (-7065 4705);
FORCEPROP 1 LAST PACK_TYPE C0805
J 0
(-7025 4675);
DISPLAY 0.510638 (-7025 4675);
FORCEPROP 1 LAST VOLTAGE 4V
J 0
(-7025 4825);
DISPLAY 0.510638 (-7025 4825);
FORCEPROP 1 LAST TOLERANCE 20%
J 0
(-7025 4775);
DISPLAY 0.510638 (-7025 4775);
FORCEPROP 1 LAST MATERIAL X6S
J 0
(-7025 4725);
DISPLAY 0.510638 (-7025 4725);
FORCEPROP 1 LAST VALUE 100UF
J 0
(-7025 4875);
DISPLAY 0.510638 (-7025 4875);
FORCEPROP 2 LAST CDS_LIB pure_quanta
J 0
(-7075 4825);
DISPLAY INVISIBLE (-7075 4825);
FORCEPROP 1 LAST PATH I16
J 0
(-7025 4975);
DISPLAY 0.978723 (-7025 4975);
PAINT WHITE (-7025 4975);
DISPLAY INVISIBLE (-7025 4975);
FORCEPROP 1 LAST PART_NUMBER CH710KMEA01
J 0
(-7025 4675);
DISPLAY 0.404255 (-7025 4675);
DISPLAY INVISIBLE (-7025 4675);
FORCEADD Q_CAP..1
(-6800 4000);
FORCEPROP 1 LAST LOCATION C199
J 0
(-6750 4100);
DISPLAY 0.808511 (-6750 4100);
PAINT WHITE (-6750 4100);
FORCEPROP 0 LAST $SEC 1
J 0
(-6750 4150);
DISPLAY 0.680851 (-6750 4150);
PAINT MONO (-6750 4150);
DISPLAY INVISIBLE (-6750 4150);
FORCEPROP 0 LAST CDS_SEC 1
J 0
(-6750 4150);
DISPLAY 0.680851 (-6750 4150);
DISPLAY INVISIBLE (-6750 4150);
FORCEPROP 1 LASTPIN (-6800 4100) $PN 1
J 0
(-6790 4080);
DISPLAY 0.787234 (-6790 4080);
PAINT MONO (-6790 4080);
FORCEPROP 1 LASTPIN (-6800 3900) $PN 2
J 0
(-6790 3880);
DISPLAY 0.787234 (-6790 3880);
PAINT MONO (-6790 3880);
FORCEPROP 1 LAST TOLERANCE 20%
J 0
(-6750 3950);
DISPLAY 0.510638 (-6750 3950);
FORCEPROP 1 LAST MATERIAL X6S
J 0
(-6750 3900);
DISPLAY 0.510638 (-6750 3900);
FORCEPROP 1 LAST PACK_TYPE C0402
J 0
(-6750 3850);
DISPLAY 0.510638 (-6750 3850);
FORCEPROP 1 LAST VALUE 10UF
J 0
(-6750 4050);
DISPLAY 0.510638 (-6750 4050);
FORCEPROP 1 LAST VOLTAGE 6.3V
J 0
(-6750 4000);
DISPLAY 0.510638 (-6750 4000);
FORCEPROP 2 LAST CDS_LIB pure_quanta
J 0
(-6800 4000);
DISPLAY INVISIBLE (-6800 4000);
FORCEPROP 1 LAST PATH I17
J 0
(-6750 4150);
DISPLAY 0.978723 (-6750 4150);
PAINT WHITE (-6750 4150);
DISPLAY INVISIBLE (-6750 4150);
FORCEPROP 1 LAST PART_NUMBER CH6101MEB01
J 0
(-6750 3850);
DISPLAY 0.978723 (-6750 3850);
DISPLAY INVISIBLE (-6750 3850);
FORCEADD Q_CAP..1
(-6600 4000);
FORCEPROP 1 LAST LOCATION C195
J 0
(-6550 4100);
DISPLAY 0.638298 (-6550 4100);
PAINT WHITE (-6550 4100);
FORCEPROP 0 LAST $SEC 1
J 0
(-6550 4125);
DISPLAY 0.680851 (-6550 4125);
PAINT MONO (-6550 4125);
DISPLAY INVISIBLE (-6550 4125);
FORCEPROP 0 LAST CDS_SEC 1
J 0
(-6550 4125);
DISPLAY 0.680851 (-6550 4125);
DISPLAY INVISIBLE (-6550 4125);
FORCEPROP 1 LASTPIN (-6600 4100) $PN 1
J 0
(-6590 4080);
DISPLAY 0.787234 (-6590 4080);
PAINT MONO (-6590 4080);
FORCEPROP 1 LASTPIN (-6600 3900) $PN 2
J 0
(-6590 3880);
DISPLAY 0.787234 (-6590 3880);
PAINT MONO (-6590 3880);
FORCEPROP 1 LAST VALUE 4.7UF
J 0
(-6550 4050);
DISPLAY 0.510638 (-6550 4050);
FORCEPROP 1 LAST PACK_TYPE 0402
J 0
(-6550 3850);
DISPLAY 0.510638 (-6550 3850);
FORCEPROP 1 LAST TOLERANCE 20%
J 0
(-6550 3950);
DISPLAY 0.510638 (-6550 3950);
FORCEPROP 1 LAST VOLTAGE 6.3V
J 0
(-6550 4000);
DISPLAY 0.510638 (-6550 4000);
FORCEPROP 1 LAST MATERIAL X6S
J 0
(-6550 3900);
DISPLAY 0.510638 (-6550 3900);
FORCEPROP 2 LAST CDS_LIB pure_quanta
J 0
(-6600 4000);
DISPLAY INVISIBLE (-6600 4000);
FORCEPROP 1 LAST PATH I18
J 0
(-6550 4150);
DISPLAY 0.978723 (-6550 4150);
PAINT WHITE (-6550 4150);
DISPLAY INVISIBLE (-6550 4150);
FORCEPROP 1 LAST PART_NUMBER CH5471MEB01
J 0
(-6550 3850);
DISPLAY 0.978723 (-6550 3850);
DISPLAY INVISIBLE (-6550 3850);
FORCEADD UNIVERSAL_GND..1
(-6400 4525);
FORCEPROP 3 LASTPIN (-6400 4575) SIG_NAME GND\g
J 0
(-6390 4585);
DISPLAY 0.659574 (-6390 4585);
PAINT MONO (-6390 4585);
DISPLAY INVISIBLE (-6390 4585);
FORCEPROP 2 LAST CDS_LIB pure_quanta_power
J 0
(-6400 4525);
DISPLAY INVISIBLE (-6400 4525);
FORCEPROP 1 LAST HDL_POWER GND
J 1
(-6375 4450);
DISPLAY 0.872340 (-6375 4450);
PAINT GREEN (-6375 4450);
DISPLAY INVISIBLE (-6375 4450);
FORCEPROP 1 LAST PATH I19
J 0
(-6325 4525);
DISPLAY 0.872340 (-6325 4525);
PAINT AQUA (-6325 4525);
DISPLAY INVISIBLE (-6325 4525);
FORCEADD Q_CAP..1
(-6375 4000);
FORCEPROP 1 LAST LOCATION C202
J 0
(-6325 4100);
DISPLAY 0.808511 (-6325 4100);
PAINT WHITE (-6325 4100);
FORCEPROP 0 LAST $SEC 1
J 0
(-6325 4150);
DISPLAY 0.680851 (-6325 4150);
PAINT MONO (-6325 4150);
DISPLAY INVISIBLE (-6325 4150);
FORCEPROP 0 LAST CDS_SEC 1
J 0
(-6325 4150);
DISPLAY 0.680851 (-6325 4150);
DISPLAY INVISIBLE (-6325 4150);
FORCEPROP 1 LASTPIN (-6375 4100) $PN 1
J 0
(-6365 4080);
DISPLAY 0.787234 (-6365 4080);
PAINT MONO (-6365 4080);
FORCEPROP 1 LASTPIN (-6375 3900) $PN 2
J 0
(-6365 3880);
DISPLAY 0.787234 (-6365 3880);
PAINT MONO (-6365 3880);
FORCEPROP 1 LAST VOLTAGE 4V
J 0
(-6325 4000);
DISPLAY 0.510638 (-6325 4000);
FORCEPROP 1 LAST VALUE 1UF
J 0
(-6325 4050);
DISPLAY 0.510638 (-6325 4050);
FORCEPROP 1 LAST MATERIAL X6S
J 0
(-6325 3900);
DISPLAY 0.510638 (-6325 3900);
FORCEPROP 1 LAST PACK_TYPE 0201
J 0
(-6325 3850);
DISPLAY 0.510638 (-6325 3850);
FORCEPROP 1 LAST TOLERANCE 20%
J 0
(-6325 3950);
DISPLAY 0.510638 (-6325 3950);
FORCEPROP 2 LAST CDS_LIB pure_quanta
J 0
(-6375 4000);
DISPLAY INVISIBLE (-6375 4000);
FORCEPROP 1 LAST PATH I20
J 0
(-6325 4150);
DISPLAY 0.978723 (-6325 4150);
PAINT WHITE (-6325 4150);
DISPLAY INVISIBLE (-6325 4150);
FORCEPROP 1 LAST PART_NUMBER CH-10KMEE00
J 0
(-6325 3850);
DISPLAY 0.510638 (-6325 3850);
DISPLAY INVISIBLE (-6325 3850);
FORCEADD UNIVERSAL_GND..1
(-6175 3675);
FORCEPROP 3 LASTPIN (-6175 3725) SIG_NAME GND\g
J 0
(-6165 3735);
DISPLAY 0.659574 (-6165 3735);
PAINT MONO (-6165 3735);
DISPLAY INVISIBLE (-6165 3735);
FORCEPROP 2 LAST CDS_LIB pure_quanta_power
J 0
(-6175 3675);
DISPLAY INVISIBLE (-6175 3675);
FORCEPROP 1 LAST HDL_POWER GND
J 1
(-6150 3600);
DISPLAY 0.872340 (-6150 3600);
PAINT GREEN (-6150 3600);
DISPLAY INVISIBLE (-6150 3600);
FORCEPROP 1 LAST PATH I21
J 0
(-6100 3675);
DISPLAY 0.872340 (-6100 3675);
PAINT AQUA (-6100 3675);
DISPLAY INVISIBLE (-6100 3675);
FORCEADD Q_CAP..1
(-6175 4000);
FORCEPROP 1 LAST LOCATION C204
J 0
(-6125 4100);
DISPLAY 0.808511 (-6125 4100);
PAINT WHITE (-6125 4100);
FORCEPROP 0 LAST $SEC 1
J 0
(-6125 4150);
DISPLAY 0.680851 (-6125 4150);
PAINT MONO (-6125 4150);
DISPLAY INVISIBLE (-6125 4150);
FORCEPROP 0 LAST CDS_SEC 1
J 0
(-6125 4150);
DISPLAY 0.680851 (-6125 4150);
DISPLAY INVISIBLE (-6125 4150);
FORCEPROP 1 LASTPIN (-6175 4100) $PN 1
J 0
(-6165 4080);
DISPLAY 0.787234 (-6165 4080);
PAINT MONO (-6165 4080);
FORCEPROP 1 LASTPIN (-6175 3900) $PN 2
J 0
(-6165 3880);
DISPLAY 0.787234 (-6165 3880);
PAINT MONO (-6165 3880);
FORCEPROP 1 LAST VOLTAGE 4V
J 0
(-6125 4000);
DISPLAY 0.510638 (-6125 4000);
FORCEPROP 1 LAST PACK_TYPE 0201
J 0
(-6125 3850);
DISPLAY 0.510638 (-6125 3850);
FORCEPROP 1 LAST MATERIAL X6S
J 0
(-6125 3900);
DISPLAY 0.510638 (-6125 3900);
FORCEPROP 1 LAST TOLERANCE 20%
J 0
(-6125 3950);
DISPLAY 0.510638 (-6125 3950);
FORCEPROP 1 LAST VALUE 1UF
J 0
(-6125 4050);
DISPLAY 0.510638 (-6125 4050);
FORCEPROP 2 LAST CDS_LIB pure_quanta
J 0
(-6175 4000);
DISPLAY INVISIBLE (-6175 4000);
FORCEPROP 1 LAST PATH I22
J 0
(-6125 4150);
DISPLAY 0.978723 (-6125 4150);
PAINT WHITE (-6125 4150);
DISPLAY INVISIBLE (-6125 4150);
FORCEPROP 1 LAST PART_NUMBER CH-10KMEE00
J 0
(-6125 3850);
DISPLAY 0.510638 (-6125 3850);
DISPLAY INVISIBLE (-6125 3850);
FORCEADD Q_CAP..1
(-5950 4000);
FORCEPROP 1 LAST LOCATION C205
J 0
(-5900 4100);
DISPLAY 0.978723 (-5900 4100);
PAINT WHITE (-5900 4100);
FORCEPROP 0 LAST $SEC 1
J 0
(-5900 4150);
DISPLAY 0.680851 (-5900 4150);
PAINT MONO (-5900 4150);
DISPLAY INVISIBLE (-5900 4150);
FORCEPROP 0 LAST CDS_SEC 1
J 0
(-5900 4150);
DISPLAY 0.680851 (-5900 4150);
DISPLAY INVISIBLE (-5900 4150);
FORCEPROP 1 LASTPIN (-5950 4100) $PN 1
J 0
(-5940 4080);
DISPLAY 0.787234 (-5940 4080);
PAINT MONO (-5940 4080);
FORCEPROP 1 LASTPIN (-5950 3900) $PN 2
J 0
(-5940 3880);
DISPLAY 0.787234 (-5940 3880);
PAINT MONO (-5940 3880);
FORCEPROP 1 LAST MATERIAL X7S
J 0
(-5900 3900);
DISPLAY 0.638298 (-5900 3900);
FORCEPROP 1 LAST PACK_TYPE C0201
J 0
(-5900 3850);
DISPLAY 0.638298 (-5900 3850);
FORCEPROP 1 LAST VOLTAGE 10V
J 0
(-5900 4000);
DISPLAY 0.638298 (-5900 4000);
FORCEPROP 1 LAST VALUE 0.1UF
J 0
(-5900 4050);
DISPLAY 0.638298 (-5900 4050);
FORCEPROP 1 LAST TOLERANCE 10%
J 0
(-5900 3950);
DISPLAY 0.638298 (-5900 3950);
FORCEPROP 2 LAST CDS_LIB pure_quanta
J 0
(-5950 4000);
DISPLAY INVISIBLE (-5950 4000);
FORCEPROP 1 LAST PATH I23
J 0
(-5900 4150);
DISPLAY 0.978723 (-5900 4150);
PAINT WHITE (-5900 4150);
DISPLAY INVISIBLE (-5900 4150);
FORCEPROP 1 LAST PART_NUMBER CH4102K6E00
J 0
(-5900 3850);
DISPLAY 0.978723 (-5900 3850);
DISPLAY INVISIBLE (-5900 3850);
FORCEADD Q_CAP..1
(-6825 4825);
FORCEPROP 1 LAST LOCATION C110
J 0
(-6775 4925);
DISPLAY 0.510638 (-6775 4925);
PAINT WHITE (-6775 4925);
FORCEPROP 0 LAST $SEC 1
J 0
(-6775 4950);
DISPLAY 0.680851 (-6775 4950);
PAINT MONO (-6775 4950);
DISPLAY INVISIBLE (-6775 4950);
FORCEPROP 0 LAST CDS_SEC 1
J 0
(-6775 4950);
DISPLAY 0.680851 (-6775 4950);
DISPLAY INVISIBLE (-6775 4950);
FORCEPROP 1 LASTPIN (-6825 4925) $PN 1
J 0
(-6815 4905);
DISPLAY 0.787234 (-6815 4905);
PAINT MONO (-6815 4905);
FORCEPROP 1 LASTPIN (-6825 4725) $PN 2
J 0
(-6815 4705);
DISPLAY 0.787234 (-6815 4705);
PAINT MONO (-6815 4705);
FORCEPROP 1 LAST VALUE 22UF
J 0
(-6775 4875);
DISPLAY 0.510638 (-6775 4875);
FORCEPROP 1 LAST MATERIAL X6S
J 0
(-6775 4725);
DISPLAY 0.510638 (-6775 4725);
FORCEPROP 1 LAST PACK_TYPE C0402
J 0
(-6775 4675);
DISPLAY 0.510638 (-6775 4675);
FORCEPROP 1 LAST TOLERANCE 20%
J 0
(-6775 4775);
DISPLAY 0.510638 (-6775 4775);
FORCEPROP 1 LAST VOLTAGE 4V
J 0
(-6775 4825);
DISPLAY 0.510638 (-6775 4825);
FORCEPROP 2 LAST CDS_LIB pure_quanta
J 0
(-6825 4825);
DISPLAY INVISIBLE (-6825 4825);
FORCEPROP 1 LAST PATH I24
J 0
(-6775 4975);
DISPLAY 0.978723 (-6775 4975);
PAINT WHITE (-6775 4975);
DISPLAY INVISIBLE (-6775 4975);
FORCEPROP 1 LAST PART_NUMBER CH622KMEB02
J 0
(-6775 4675);
DISPLAY 0.978723 (-6775 4675);
DISPLAY INVISIBLE (-6775 4675);
FORCEADD Q_CAP..1
(-6575 4800);
FORCEPROP 1 LAST LOCATION C127
J 0
(-6525 4900);
DISPLAY 0.638298 (-6525 4900);
PAINT WHITE (-6525 4900);
FORCEPROP 0 LAST $SEC 1
J 0
(-6525 4950);
DISPLAY 0.680851 (-6525 4950);
PAINT MONO (-6525 4950);
DISPLAY INVISIBLE (-6525 4950);
FORCEPROP 0 LAST CDS_SEC 1
J 0
(-6525 4950);
DISPLAY 0.680851 (-6525 4950);
DISPLAY INVISIBLE (-6525 4950);
FORCEPROP 1 LASTPIN (-6575 4900) $PN 1
J 0
(-6565 4880);
DISPLAY 0.787234 (-6565 4880);
PAINT MONO (-6565 4880);
FORCEPROP 1 LASTPIN (-6575 4700) $PN 2
J 0
(-6565 4680);
DISPLAY 0.787234 (-6565 4680);
PAINT MONO (-6565 4680);
FORCEPROP 1 LAST MATERIAL X6S
J 0
(-6525 4700);
DISPLAY 0.510638 (-6525 4700);
FORCEPROP 1 LAST VOLTAGE 6.3V
J 0
(-6525 4800);
DISPLAY 0.510638 (-6525 4800);
FORCEPROP 1 LAST TOLERANCE 20%
J 0
(-6525 4750);
DISPLAY 0.510638 (-6525 4750);
FORCEPROP 1 LAST VALUE 10UF
J 0
(-6525 4850);
DISPLAY 0.510638 (-6525 4850);
FORCEPROP 1 LAST PACK_TYPE C0402
J 0
(-6525 4650);
DISPLAY 0.510638 (-6525 4650);
FORCEPROP 2 LAST CDS_LIB pure_quanta
J 0
(-6575 4800);
DISPLAY INVISIBLE (-6575 4800);
FORCEPROP 1 LAST PATH I25
J 0
(-6525 4950);
DISPLAY 0.978723 (-6525 4950);
PAINT WHITE (-6525 4950);
DISPLAY INVISIBLE (-6525 4950);
FORCEPROP 1 LAST PART_NUMBER CH6101MEB01
J 0
(-6525 4650);
DISPLAY 0.978723 (-6525 4650);
DISPLAY INVISIBLE (-6525 4650);
FORCEADD Q_CAP..1
(-6325 4800);
FORCEPROP 1 LAST LOCATION C200
J 0
(-6275 4900);
DISPLAY 0.638298 (-6275 4900);
PAINT WHITE (-6275 4900);
FORCEPROP 0 LAST $SEC 1
J 0
(-6275 4950);
DISPLAY 0.680851 (-6275 4950);
PAINT MONO (-6275 4950);
DISPLAY INVISIBLE (-6275 4950);
FORCEPROP 0 LAST CDS_SEC 1
J 0
(-6275 4950);
DISPLAY 0.680851 (-6275 4950);
DISPLAY INVISIBLE (-6275 4950);
FORCEPROP 1 LASTPIN (-6325 4900) $PN 1
J 0
(-6315 4880);
DISPLAY 0.787234 (-6315 4880);
PAINT MONO (-6315 4880);
FORCEPROP 1 LASTPIN (-6325 4700) $PN 2
J 0
(-6315 4680);
DISPLAY 0.787234 (-6315 4680);
PAINT MONO (-6315 4680);
FORCEPROP 1 LAST VOLTAGE 6.3V
J 0
(-6275 4800);
DISPLAY 0.510638 (-6275 4800);
FORCEPROP 1 LAST VALUE 4.7UF
J 0
(-6275 4850);
DISPLAY 0.510638 (-6275 4850);
FORCEPROP 1 LAST TOLERANCE 20%
J 0
(-6275 4750);
DISPLAY 0.510638 (-6275 4750);
FORCEPROP 1 LAST MATERIAL X6S
J 0
(-6275 4700);
DISPLAY 0.510638 (-6275 4700);
FORCEPROP 1 LAST PACK_TYPE 0402
J 0
(-6275 4650);
DISPLAY 0.510638 (-6275 4650);
FORCEPROP 2 LAST CDS_LIB pure_quanta
J 0
(-6325 4800);
DISPLAY INVISIBLE (-6325 4800);
FORCEPROP 1 LAST PATH I26
J 0
(-6275 4950);
DISPLAY 0.978723 (-6275 4950);
PAINT WHITE (-6275 4950);
DISPLAY INVISIBLE (-6275 4950);
FORCEPROP 1 LAST PART_NUMBER CH5471MEB01
J 0
(-6275 4650);
DISPLAY 0.978723 (-6275 4650);
DISPLAY INVISIBLE (-6275 4650);
FORCEADD Q_CAP..1
(-5700 4000);
FORCEPROP 1 LAST LOCATION C217
J 0
(-5650 4100);
DISPLAY 0.978723 (-5650 4100);
PAINT WHITE (-5650 4100);
FORCEPROP 0 LAST $SEC 1
J 0
(-5650 4150);
DISPLAY 0.680851 (-5650 4150);
PAINT MONO (-5650 4150);
DISPLAY INVISIBLE (-5650 4150);
FORCEPROP 0 LAST CDS_SEC 1
J 0
(-5650 4150);
DISPLAY 0.680851 (-5650 4150);
DISPLAY INVISIBLE (-5650 4150);
FORCEPROP 1 LASTPIN (-5700 4100) $PN 1
J 0
(-5690 4080);
DISPLAY 0.787234 (-5690 4080);
PAINT MONO (-5690 4080);
FORCEPROP 1 LASTPIN (-5700 3900) $PN 2
J 0
(-5690 3880);
DISPLAY 0.787234 (-5690 3880);
PAINT MONO (-5690 3880);
FORCEPROP 1 LAST PACK_TYPE C0201
J 0
(-5650 3850);
DISPLAY 0.638298 (-5650 3850);
FORCEPROP 1 LAST MATERIAL X7S
J 0
(-5650 3900);
DISPLAY 0.638298 (-5650 3900);
FORCEPROP 1 LAST VALUE 0.1UF
J 0
(-5650 4050);
DISPLAY 0.638298 (-5650 4050);
FORCEPROP 1 LAST VOLTAGE 10V
J 0
(-5650 4000);
DISPLAY 0.638298 (-5650 4000);
FORCEPROP 1 LAST TOLERANCE 10%
J 0
(-5650 3950);
DISPLAY 0.638298 (-5650 3950);
FORCEPROP 2 LAST CDS_LIB pure_quanta
J 0
(-5700 4000);
DISPLAY INVISIBLE (-5700 4000);
FORCEPROP 1 LAST PATH I27
J 0
(-5650 4150);
DISPLAY 0.978723 (-5650 4150);
PAINT WHITE (-5650 4150);
DISPLAY INVISIBLE (-5650 4150);
FORCEPROP 1 LAST PART_NUMBER CH4102K6E00
J 0
(-5650 3850);
DISPLAY 0.978723 (-5650 3850);
DISPLAY INVISIBLE (-5650 3850);
FORCEADD Q_CAP..1
(-5450 4000);
FORCEPROP 1 LAST LOCATION C287
J 0
(-5400 4100);
DISPLAY 0.978723 (-5400 4100);
PAINT WHITE (-5400 4100);
FORCEPROP 0 LAST $SEC 1
J 0
(-5400 4150);
DISPLAY 0.680851 (-5400 4150);
PAINT MONO (-5400 4150);
DISPLAY INVISIBLE (-5400 4150);
FORCEPROP 0 LAST CDS_SEC 1
J 0
(-5400 4150);
DISPLAY 0.680851 (-5400 4150);
DISPLAY INVISIBLE (-5400 4150);
FORCEPROP 1 LASTPIN (-5450 4100) $PN 1
J 0
(-5440 4080);
DISPLAY 0.787234 (-5440 4080);
PAINT MONO (-5440 4080);
FORCEPROP 1 LASTPIN (-5450 3900) $PN 2
J 0
(-5440 3880);
DISPLAY 0.787234 (-5440 3880);
PAINT MONO (-5440 3880);
FORCEPROP 1 LAST VOLTAGE 10V
J 0
(-5400 4000);
DISPLAY 0.638298 (-5400 4000);
FORCEPROP 1 LAST MATERIAL X7S
J 0
(-5400 3900);
DISPLAY 0.638298 (-5400 3900);
FORCEPROP 1 LAST TOLERANCE 10%
J 0
(-5400 3950);
DISPLAY 0.638298 (-5400 3950);
FORCEPROP 1 LAST PACK_TYPE C0201
J 0
(-5400 3850);
DISPLAY 0.638298 (-5400 3850);
FORCEPROP 1 LAST VALUE 0.1UF
J 0
(-5400 4050);
DISPLAY 0.638298 (-5400 4050);
FORCEPROP 2 LAST CDS_LIB pure_quanta
J 0
(-5450 4000);
DISPLAY INVISIBLE (-5450 4000);
FORCEPROP 1 LAST PATH I28
J 0
(-5400 4150);
DISPLAY 0.978723 (-5400 4150);
PAINT WHITE (-5400 4150);
DISPLAY INVISIBLE (-5400 4150);
FORCEPROP 1 LAST PART_NUMBER CH4102K6E00
J 0
(-5400 3850);
DISPLAY 0.978723 (-5400 3850);
DISPLAY INVISIBLE (-5400 3850);
FORCEADD Q_CAP..1
(-5175 4000);
FORCEPROP 1 LAST LOCATION C288
J 0
(-5125 4100);
DISPLAY 0.978723 (-5125 4100);
PAINT WHITE (-5125 4100);
FORCEPROP 0 LAST $SEC 1
J 0
(-5125 4150);
DISPLAY 0.680851 (-5125 4150);
PAINT MONO (-5125 4150);
DISPLAY INVISIBLE (-5125 4150);
FORCEPROP 0 LAST CDS_SEC 1
J 0
(-5125 4150);
DISPLAY 0.680851 (-5125 4150);
DISPLAY INVISIBLE (-5125 4150);
FORCEPROP 1 LASTPIN (-5175 4100) $PN 1
J 0
(-5165 4080);
DISPLAY 0.787234 (-5165 4080);
PAINT MONO (-5165 4080);
FORCEPROP 1 LASTPIN (-5175 3900) $PN 2
J 0
(-5165 3880);
DISPLAY 0.787234 (-5165 3880);
PAINT MONO (-5165 3880);
FORCEPROP 1 LAST VALUE 0.1UF
J 0
(-5125 4050);
DISPLAY 0.638298 (-5125 4050);
FORCEPROP 1 LAST MATERIAL X7S
J 0
(-5125 3900);
DISPLAY 0.638298 (-5125 3900);
FORCEPROP 1 LAST TOLERANCE 10%
J 0
(-5125 3950);
DISPLAY 0.638298 (-5125 3950);
FORCEPROP 1 LAST PACK_TYPE C0201
J 0
(-5125 3850);
DISPLAY 0.638298 (-5125 3850);
FORCEPROP 1 LAST VOLTAGE 10V
J 0
(-5125 4000);
DISPLAY 0.638298 (-5125 4000);
FORCEPROP 2 LAST CDS_LIB pure_quanta
J 0
(-5175 4000);
DISPLAY INVISIBLE (-5175 4000);
FORCEPROP 1 LAST PATH I29
J 0
(-5125 4150);
DISPLAY 0.978723 (-5125 4150);
PAINT WHITE (-5125 4150);
DISPLAY INVISIBLE (-5125 4150);
FORCEPROP 1 LAST PART_NUMBER CH4102K6E00
J 0
(-5125 3850);
DISPLAY 0.978723 (-5125 3850);
DISPLAY INVISIBLE (-5125 3850);
FORCEADD P1V0..1
(-8175 5100);
FORCEPROP 3 LASTPIN (-8175 5050) SIG_NAME P1V8_CPU1_RT_1D\g
J 0
(-8165 5060);
DISPLAY 0.659574 (-8165 5060);
PAINT MONO (-8165 5060);
DISPLAY INVISIBLE (-8165 5060);
FORCEPROP 1 LAST HDL_POWER P1V8_CPU1_RT_1D
J 1
(-8175 5150);
DISPLAY 0.489362 (-8175 5150);
PAINT SKYBLUE (-8175 5150);
FORCEPROP 2 LAST CDS_LIB pure_quanta_power
J 0
(-8175 5100);
DISPLAY INVISIBLE (-8175 5100);
FORCEPROP 1 LAST PATH I3
J 0
(-8125 5125);
DISPLAY 0.872340 (-8125 5125);
PAINT AQUA (-8125 5125);
DISPLAY INVISIBLE (-8125 5125);
FORCEADD Q_INDUCTOR..1
(-3850 4275);
FORCEPROP 1 LAST LOCATION L6
J 0
(-3975 4435);
DISPLAY 0.723404 (-3975 4435);
PAINT GREEN (-3975 4435);
FORCEPROP 0 LAST $SEC 1
J 0
(-3975 4575);
DISPLAY 0.680851 (-3975 4575);
PAINT MONO (-3975 4575);
DISPLAY INVISIBLE (-3975 4575);
FORCEPROP 0 LAST CDS_SEC 1
J 0
(-3975 4575);
DISPLAY 0.680851 (-3975 4575);
DISPLAY INVISIBLE (-3975 4575);
FORCEPROP 0 LASTPIN (-3950 4250) $PN 1
J 2
(-3960 4260);
DISPLAY 0.680851 (-3960 4260);
PAINT MONO (-3960 4260);
FORCEPROP 0 LASTPIN (-3750 4250) $PN 2
J 0
(-3740 4260);
DISPLAY 0.680851 (-3740 4260);
PAINT MONO (-3740 4260);
FORCEPROP 1 LAST MATERIAL IND
J 0
(-3975 4330);
DISPLAY 0.723404 (-3975 4330);
PAINT GREEN (-3975 4330);
FORCEPROP 2 LAST PACK_TYPE SMLF
J 0
(-3975 4475);
DISPLAY 0.680851 (-3975 4475);
FORCEPROP 2 LAST VALUE 100NH/16A
J 0
(-3975 4525);
DISPLAY 0.680851 (-3975 4525);
FORCEPROP 1 LAST NEEDS_NO_SIZE TRUE
J 0
(-3850 4275);
DISPLAY 0.468085 (-3850 4275);
PAINT GREEN (-3850 4275);
DISPLAY INVISIBLE (-3850 4275);
FORCEPROP 2 LAST CDS_LIB pure_quanta
J 0
(-3850 4275);
DISPLAY INVISIBLE (-3850 4275);
FORCEPROP 1 LAST PATH I30
J 0
(-3775 4330);
DISPLAY 0.723404 (-3775 4330);
PAINT GREEN (-3775 4330);
DISPLAY INVISIBLE (-3775 4330);
FORCEPROP 1 LAST PART_NUMBER CV+10G0MZ04
J 0
(-3975 4385);
DISPLAY 0.723404 (-3975 4385);
PAINT GREEN (-3975 4385);
DISPLAY INVISIBLE (-3975 4385);
FORCEADD VCC_CORE..1
(-4325 5775);
FORCEPROP 3 LASTPIN (-4325 5725) SIG_NAME P0V9_CPU1_RT_2D\g
J 0
(-4315 5735);
DISPLAY 0.659574 (-4315 5735);
PAINT MONO (-4315 5735);
DISPLAY INVISIBLE (-4315 5735);
FORCEPROP 1 LAST HDL_POWER P0V9_CPU1_RT_2D
J 1
(-4325 5825);
DISPLAY 0.617021 (-4325 5825);
PAINT GREEN (-4325 5825);
FORCEPROP 2 LAST CDS_LIB pure_quanta_power
J 0
(-4325 5775);
DISPLAY INVISIBLE (-4325 5775);
FORCEPROP 1 LAST PATH I31
J 0
(-4275 5800);
DISPLAY 0.872340 (-4275 5800);
PAINT AQUA (-4275 5800);
DISPLAY INVISIBLE (-4275 5800);
FORCEADD VCC_CORE..1
(-3175 1475);
FORCEPROP 3 LASTPIN (-3175 1425) SIG_NAME P0V9_CPU1_RT1_2A_2D\g
J 0
(-3165 1435);
DISPLAY 0.659574 (-3165 1435);
PAINT MONO (-3165 1435);
DISPLAY INVISIBLE (-3165 1435);
FORCEPROP 1 LAST HDL_POWER P0V9_CPU1_RT1_2A_2D
J 1
(-3175 1525);
DISPLAY 0.617021 (-3175 1525);
PAINT GREEN (-3175 1525);
FORCEPROP 2 LAST CDS_LIB pure_quanta_power
J 0
(-3175 1475);
DISPLAY INVISIBLE (-3175 1475);
FORCEPROP 1 LAST PATH I33
J 0
(-3125 1500);
DISPLAY 0.872340 (-3125 1500);
PAINT AQUA (-3125 1500);
DISPLAY INVISIBLE (-3125 1500);
FORCEADD Q_CAP..1
(-2800 950);
FORCEPROP 1 LAST LOCATION C313
J 0
(-2750 1050);
DISPLAY 0.978723 (-2750 1050);
PAINT WHITE (-2750 1050);
FORCEPROP 0 LAST $SEC 1
J 0
(-2750 1100);
DISPLAY 0.680851 (-2750 1100);
PAINT MONO (-2750 1100);
DISPLAY INVISIBLE (-2750 1100);
FORCEPROP 0 LAST CDS_SEC 1
J 0
(-2750 1100);
DISPLAY 0.680851 (-2750 1100);
DISPLAY INVISIBLE (-2750 1100);
FORCEPROP 1 LASTPIN (-2800 1050) $PN 1
J 0
(-2790 1030);
DISPLAY 0.787234 (-2790 1030);
PAINT MONO (-2790 1030);
FORCEPROP 1 LASTPIN (-2800 850) $PN 2
J 0
(-2790 830);
DISPLAY 0.787234 (-2790 830);
PAINT MONO (-2790 830);
FORCEPROP 1 LAST PACK_TYPE C0201
J 0
(-2750 800);
DISPLAY 0.638298 (-2750 800);
FORCEPROP 1 LAST TOLERANCE 10%
J 0
(-2750 900);
DISPLAY 0.638298 (-2750 900);
FORCEPROP 1 LAST MATERIAL X7S
J 0
(-2750 850);
DISPLAY 0.638298 (-2750 850);
FORCEPROP 1 LAST VOLTAGE 10V
J 0
(-2750 950);
DISPLAY 0.638298 (-2750 950);
FORCEPROP 1 LAST VALUE 0.1UF
J 0
(-2750 1000);
DISPLAY 0.638298 (-2750 1000);
FORCEPROP 2 LAST CDS_LIB pure_quanta
J 0
(-2800 950);
DISPLAY INVISIBLE (-2800 950);
FORCEPROP 1 LAST PATH I34
J 0
(-2750 1100);
DISPLAY 0.978723 (-2750 1100);
PAINT WHITE (-2750 1100);
DISPLAY INVISIBLE (-2750 1100);
FORCEPROP 1 LAST PART_NUMBER CH4102K6E00
J 0
(-2750 800);
DISPLAY 0.978723 (-2750 800);
DISPLAY INVISIBLE (-2750 800);
FORCEADD UNIVERSAL_GND..1
(-2350 625);
FORCEPROP 3 LASTPIN (-2350 675) SIG_NAME GND\g
J 0
(-2340 685);
DISPLAY 0.659574 (-2340 685);
PAINT MONO (-2340 685);
DISPLAY INVISIBLE (-2340 685);
FORCEPROP 2 LAST CDS_LIB pure_quanta_power
J 0
(-2350 625);
DISPLAY INVISIBLE (-2350 625);
FORCEPROP 1 LAST HDL_POWER GND
J 1
(-2325 550);
DISPLAY 0.872340 (-2325 550);
PAINT GREEN (-2325 550);
DISPLAY INVISIBLE (-2325 550);
FORCEPROP 1 LAST PATH I35
J 0
(-2275 625);
DISPLAY 0.872340 (-2275 625);
PAINT AQUA (-2275 625);
DISPLAY INVISIBLE (-2275 625);
FORCEADD Q_CAP..1
(-2250 950);
FORCEPROP 1 LAST LOCATION C316
J 0
(-2200 1050);
DISPLAY 0.978723 (-2200 1050);
PAINT WHITE (-2200 1050);
FORCEPROP 0 LAST $SEC 1
J 0
(-2200 1100);
DISPLAY 0.680851 (-2200 1100);
PAINT MONO (-2200 1100);
DISPLAY INVISIBLE (-2200 1100);
FORCEPROP 0 LAST CDS_SEC 1
J 0
(-2200 1100);
DISPLAY 0.680851 (-2200 1100);
DISPLAY INVISIBLE (-2200 1100);
FORCEPROP 1 LASTPIN (-2250 1050) $PN 1
J 0
(-2240 1030);
DISPLAY 0.787234 (-2240 1030);
PAINT MONO (-2240 1030);
FORCEPROP 1 LASTPIN (-2250 850) $PN 2
J 0
(-2240 830);
DISPLAY 0.787234 (-2240 830);
PAINT MONO (-2240 830);
FORCEPROP 1 LAST PACK_TYPE C0201
J 0
(-2200 800);
DISPLAY 0.638298 (-2200 800);
FORCEPROP 1 LAST MATERIAL X7S
J 0
(-2200 850);
DISPLAY 0.638298 (-2200 850);
FORCEPROP 1 LAST VOLTAGE 10V
J 0
(-2200 950);
DISPLAY 0.638298 (-2200 950);
FORCEPROP 1 LAST TOLERANCE 10%
J 0
(-2200 900);
DISPLAY 0.638298 (-2200 900);
FORCEPROP 1 LAST VALUE 0.1UF
J 0
(-2200 1000);
DISPLAY 0.638298 (-2200 1000);
FORCEPROP 2 LAST CDS_LIB pure_quanta
J 0
(-2250 950);
DISPLAY INVISIBLE (-2250 950);
FORCEPROP 1 LAST PATH I37
J 0
(-2200 1100);
DISPLAY 0.978723 (-2200 1100);
PAINT WHITE (-2200 1100);
DISPLAY INVISIBLE (-2200 1100);
FORCEPROP 1 LAST PART_NUMBER CH4102K6E00
J 0
(-2200 800);
DISPLAY 0.978723 (-2200 800);
DISPLAY INVISIBLE (-2200 800);
FORCEADD Q_CAP..1
(-3225 2050);
FORCEPROP 1 LAST LOCATION C340
J 0
(-3175 2150);
DISPLAY 0.978723 (-3175 2150);
PAINT WHITE (-3175 2150);
FORCEPROP 0 LAST $SEC 1
J 0
(-3175 2200);
DISPLAY 0.680851 (-3175 2200);
PAINT MONO (-3175 2200);
DISPLAY INVISIBLE (-3175 2200);
FORCEPROP 0 LAST CDS_SEC 1
J 0
(-3175 2200);
DISPLAY 0.680851 (-3175 2200);
DISPLAY INVISIBLE (-3175 2200);
FORCEPROP 1 LASTPIN (-3225 2150) $PN 1
J 0
(-3215 2130);
DISPLAY 0.787234 (-3215 2130);
PAINT MONO (-3215 2130);
FORCEPROP 1 LASTPIN (-3225 1950) $PN 2
J 0
(-3215 1930);
DISPLAY 0.787234 (-3215 1930);
PAINT MONO (-3215 1930);
FORCEPROP 1 LAST VALUE 0.1UF
J 0
(-3175 2100);
DISPLAY 0.638298 (-3175 2100);
FORCEPROP 1 LAST MATERIAL X7S
J 0
(-3175 1950);
DISPLAY 0.638298 (-3175 1950);
FORCEPROP 1 LAST PACK_TYPE C0201
J 0
(-3175 1900);
DISPLAY 0.638298 (-3175 1900);
FORCEPROP 1 LAST VOLTAGE 10V
J 0
(-3175 2050);
DISPLAY 0.638298 (-3175 2050);
FORCEPROP 1 LAST TOLERANCE 10%
J 0
(-3175 2000);
DISPLAY 0.638298 (-3175 2000);
FORCEPROP 2 LAST CDS_LIB pure_quanta
J 0
(-3225 2050);
DISPLAY INVISIBLE (-3225 2050);
FORCEPROP 1 LAST PATH I38
J 0
(-3175 2200);
DISPLAY 0.978723 (-3175 2200);
PAINT WHITE (-3175 2200);
DISPLAY INVISIBLE (-3175 2200);
FORCEPROP 1 LAST PART_NUMBER CH4102K6E00
J 0
(-3175 1900);
DISPLAY 0.978723 (-3175 1900);
DISPLAY INVISIBLE (-3175 1900);
FORCEADD Q_CAP..1
(-2925 2050);
FORCEPROP 1 LAST LOCATION C344
J 0
(-2875 2150);
DISPLAY 0.978723 (-2875 2150);
PAINT WHITE (-2875 2150);
FORCEPROP 0 LAST $SEC 1
J 0
(-2875 2200);
DISPLAY 0.680851 (-2875 2200);
PAINT MONO (-2875 2200);
DISPLAY INVISIBLE (-2875 2200);
FORCEPROP 0 LAST CDS_SEC 1
J 0
(-2875 2200);
DISPLAY 0.680851 (-2875 2200);
DISPLAY INVISIBLE (-2875 2200);
FORCEPROP 1 LASTPIN (-2925 2150) $PN 1
J 0
(-2915 2130);
DISPLAY 0.787234 (-2915 2130);
PAINT MONO (-2915 2130);
FORCEPROP 1 LASTPIN (-2925 1950) $PN 2
J 0
(-2915 1930);
DISPLAY 0.787234 (-2915 1930);
PAINT MONO (-2915 1930);
FORCEPROP 1 LAST VALUE 0.1UF
J 0
(-2875 2100);
DISPLAY 0.638298 (-2875 2100);
FORCEPROP 1 LAST MATERIAL X7S
J 0
(-2875 1950);
DISPLAY 0.638298 (-2875 1950);
FORCEPROP 1 LAST PACK_TYPE C0201
J 0
(-2875 1900);
DISPLAY 0.638298 (-2875 1900);
FORCEPROP 1 LAST VOLTAGE 10V
J 0
(-2875 2050);
DISPLAY 0.638298 (-2875 2050);
FORCEPROP 1 LAST TOLERANCE 10%
J 0
(-2875 2000);
DISPLAY 0.638298 (-2875 2000);
FORCEPROP 2 LAST CDS_LIB pure_quanta
J 0
(-2925 2050);
DISPLAY INVISIBLE (-2925 2050);
FORCEPROP 1 LAST PATH I39
J 0
(-2875 2200);
DISPLAY 0.978723 (-2875 2200);
PAINT WHITE (-2875 2200);
DISPLAY INVISIBLE (-2875 2200);
FORCEPROP 1 LAST PART_NUMBER CH4102K6E00
J 0
(-2875 1900);
DISPLAY 0.978723 (-2875 1900);
DISPLAY INVISIBLE (-2875 1900);
FORCEADD Q_RES..1
(-7725 3375);
FORCEPROP 1 LAST LOCATION R664
J 0
(-8000 3375);
DISPLAY 0.787234 (-8000 3375);
FORCEPROP 2 LAST SEC 1
J 0
(-7775 3575);
DISPLAY 0.680851 (-7775 3575);
PAINT MONO (-7775 3575);
DISPLAY INVISIBLE (-7775 3575);
FORCEPROP 1 LASTPIN (-7825 3375) $PN 1
J 0
(-7813 3387);
DISPLAY 0.787234 (-7813 3387);
PAINT MONO (-7813 3387);
FORCEPROP 1 LASTPIN (-7625 3375) $PN 2
J 0
(-7663 3387);
DISPLAY 0.787234 (-7663 3387);
PAINT MONO (-7663 3387);
FORCEPROP 1 LAST WATTAGE 1/16W
J 2
(-7725 3275);
DISPLAY 0.638298 (-7725 3275);
FORCEPROP 1 LAST TOLERANCE 5%
J 0
(-7675 3325);
DISPLAY 0.638298 (-7675 3325);
FORCEPROP 1 LAST PACK_TYPE 0402LF
J 0
(-7875 3325);
DISPLAY 0.638298 (-7875 3325);
FORCEPROP 1 LAST VALUE 0
J 2
(-7575 3400);
DISPLAY 0.638298 (-7575 3400);
FORCEPROP 1 LAST MATERIAL EMPTY
J 0
(-7700 3275);
DISPLAY 0.638298 (-7700 3275);
FORCEPROP 2 LAST CDS_LIB pure_quanta
J 0
(-7725 3375);
DISPLAY INVISIBLE (-7725 3375);
FORCEPROP 2 LAST SEC_TYPE 0402LF
J 0
(-7775 3575);
DISPLAY 0.680851 (-7775 3575);
DISPLAY INVISIBLE (-7775 3575);
FORCEPROP 1 LAST PATH I4
J 0
(-7775 3525);
DISPLAY 0.978723 (-7775 3525);
PAINT WHITE (-7775 3525);
DISPLAY INVISIBLE (-7775 3525);
FORCEPROP 1 LAST PART_NUMBER CS00002JB13
J 0
(-7775 3475);
DISPLAY 0.978723 (-7775 3475);
DISPLAY INVISIBLE (-7775 3475);
FORCEADD Q_CAP..1
(-3500 2750);
FORCEPROP 1 LAST LOCATION C294
J 0
(-3450 2850);
DISPLAY 0.978723 (-3450 2850);
PAINT WHITE (-3450 2850);
FORCEPROP 0 LAST $SEC 1
J 0
(-3450 2900);
DISPLAY 0.680851 (-3450 2900);
PAINT MONO (-3450 2900);
DISPLAY INVISIBLE (-3450 2900);
FORCEPROP 0 LAST CDS_SEC 1
J 0
(-3450 2900);
DISPLAY 0.680851 (-3450 2900);
DISPLAY INVISIBLE (-3450 2900);
FORCEPROP 1 LASTPIN (-3500 2850) $PN 1
J 0
(-3490 2830);
DISPLAY 0.787234 (-3490 2830);
PAINT MONO (-3490 2830);
FORCEPROP 1 LASTPIN (-3500 2650) $PN 2
J 0
(-3490 2630);
DISPLAY 0.787234 (-3490 2630);
PAINT MONO (-3490 2630);
FORCEPROP 1 LAST VALUE 1UF
J 0
(-3450 2800);
DISPLAY 0.510638 (-3450 2800);
FORCEPROP 1 LAST VOLTAGE 4V
J 0
(-3450 2750);
DISPLAY 0.510638 (-3450 2750);
FORCEPROP 1 LAST PACK_TYPE 0201
J 0
(-3450 2600);
DISPLAY 0.510638 (-3450 2600);
FORCEPROP 1 LAST MATERIAL X6S
J 0
(-3450 2650);
DISPLAY 0.510638 (-3450 2650);
FORCEPROP 1 LAST TOLERANCE 20%
J 0
(-3450 2700);
DISPLAY 0.510638 (-3450 2700);
FORCEPROP 2 LAST CDS_LIB pure_quanta
J 0
(-3500 2750);
DISPLAY INVISIBLE (-3500 2750);
FORCEPROP 1 LAST PATH I40
J 0
(-3450 2900);
DISPLAY 0.978723 (-3450 2900);
PAINT WHITE (-3450 2900);
DISPLAY INVISIBLE (-3450 2900);
FORCEPROP 1 LAST PART_NUMBER CH-10KMEE00
J 0
(-3450 2600);
DISPLAY 0.510638 (-3450 2600);
DISPLAY INVISIBLE (-3450 2600);
FORCEADD Q_CAP..1
(-3500 3375);
FORCEPROP 1 LAST LOCATION C332
J 0
(-3450 3475);
DISPLAY 0.978723 (-3450 3475);
PAINT WHITE (-3450 3475);
FORCEPROP 0 LAST $SEC 1
J 0
(-3450 3525);
DISPLAY 0.680851 (-3450 3525);
PAINT MONO (-3450 3525);
DISPLAY INVISIBLE (-3450 3525);
FORCEPROP 0 LAST CDS_SEC 1
J 0
(-3450 3525);
DISPLAY 0.680851 (-3450 3525);
DISPLAY INVISIBLE (-3450 3525);
FORCEPROP 1 LASTPIN (-3500 3475) $PN 1
J 0
(-3490 3455);
DISPLAY 0.787234 (-3490 3455);
PAINT MONO (-3490 3455);
FORCEPROP 1 LASTPIN (-3500 3275) $PN 2
J 0
(-3490 3255);
DISPLAY 0.787234 (-3490 3255);
PAINT MONO (-3490 3255);
FORCEPROP 1 LAST VOLTAGE 6.3V
J 0
(-3450 3375);
DISPLAY 0.510638 (-3450 3375);
FORCEPROP 1 LAST VALUE 10UF
J 0
(-3450 3425);
DISPLAY 0.510638 (-3450 3425);
FORCEPROP 1 LAST TOLERANCE 20%
J 0
(-3450 3325);
DISPLAY 0.510638 (-3450 3325);
FORCEPROP 1 LAST MATERIAL X6S
J 0
(-3450 3275);
DISPLAY 0.510638 (-3450 3275);
FORCEPROP 1 LAST PACK_TYPE C0402
J 0
(-3450 3225);
DISPLAY 0.510638 (-3450 3225);
FORCEPROP 2 LAST CDS_LIB pure_quanta
J 0
(-3500 3375);
DISPLAY INVISIBLE (-3500 3375);
FORCEPROP 1 LAST PATH I41
J 0
(-3450 3525);
DISPLAY 0.978723 (-3450 3525);
PAINT WHITE (-3450 3525);
DISPLAY INVISIBLE (-3450 3525);
FORCEPROP 1 LAST PART_NUMBER CH6101MEB01
J 0
(-3450 3225);
DISPLAY 0.978723 (-3450 3225);
DISPLAY INVISIBLE (-3450 3225);
FORCEADD Q_CAP..1
(-3275 2750);
FORCEPROP 1 LAST LOCATION C307
J 0
(-3225 2850);
DISPLAY 0.978723 (-3225 2850);
PAINT WHITE (-3225 2850);
FORCEPROP 0 LAST $SEC 1
J 0
(-3225 2900);
DISPLAY 0.680851 (-3225 2900);
PAINT MONO (-3225 2900);
DISPLAY INVISIBLE (-3225 2900);
FORCEPROP 0 LAST CDS_SEC 1
J 0
(-3225 2900);
DISPLAY 0.680851 (-3225 2900);
DISPLAY INVISIBLE (-3225 2900);
FORCEPROP 1 LASTPIN (-3275 2850) $PN 1
J 0
(-3265 2830);
DISPLAY 0.787234 (-3265 2830);
PAINT MONO (-3265 2830);
FORCEPROP 1 LASTPIN (-3275 2650) $PN 2
J 0
(-3265 2630);
DISPLAY 0.787234 (-3265 2630);
PAINT MONO (-3265 2630);
FORCEPROP 1 LAST VALUE 1UF
J 0
(-3225 2800);
DISPLAY 0.510638 (-3225 2800);
FORCEPROP 1 LAST TOLERANCE 20%
J 0
(-3225 2700);
DISPLAY 0.510638 (-3225 2700);
FORCEPROP 1 LAST PACK_TYPE 0201
J 0
(-3225 2600);
DISPLAY 0.510638 (-3225 2600);
FORCEPROP 1 LAST MATERIAL X6S
J 0
(-3225 2650);
DISPLAY 0.510638 (-3225 2650);
FORCEPROP 1 LAST VOLTAGE 4V
J 0
(-3225 2750);
DISPLAY 0.510638 (-3225 2750);
FORCEPROP 2 LAST CDS_LIB pure_quanta
J 0
(-3275 2750);
DISPLAY INVISIBLE (-3275 2750);
FORCEPROP 1 LAST PATH I42
J 0
(-3225 2900);
DISPLAY 0.978723 (-3225 2900);
PAINT WHITE (-3225 2900);
DISPLAY INVISIBLE (-3225 2900);
FORCEPROP 1 LAST PART_NUMBER CH-10KMEE00
J 0
(-3225 2600);
DISPLAY 0.510638 (-3225 2600);
DISPLAY INVISIBLE (-3225 2600);
FORCEADD Q_CAP..1
(-3025 2750);
FORCEPROP 1 LAST LOCATION C326
J 0
(-2975 2850);
DISPLAY 0.978723 (-2975 2850);
PAINT WHITE (-2975 2850);
FORCEPROP 0 LAST $SEC 1
J 0
(-2975 2900);
DISPLAY 0.680851 (-2975 2900);
PAINT MONO (-2975 2900);
DISPLAY INVISIBLE (-2975 2900);
FORCEPROP 0 LAST CDS_SEC 1
J 0
(-2975 2900);
DISPLAY 0.680851 (-2975 2900);
DISPLAY INVISIBLE (-2975 2900);
FORCEPROP 1 LASTPIN (-3025 2850) $PN 1
J 0
(-3015 2830);
DISPLAY 0.787234 (-3015 2830);
PAINT MONO (-3015 2830);
FORCEPROP 1 LASTPIN (-3025 2650) $PN 2
J 0
(-3015 2630);
DISPLAY 0.787234 (-3015 2630);
PAINT MONO (-3015 2630);
FORCEPROP 1 LAST VALUE 1UF
J 0
(-2975 2800);
DISPLAY 0.510638 (-2975 2800);
FORCEPROP 1 LAST VOLTAGE 4V
J 0
(-2975 2750);
DISPLAY 0.510638 (-2975 2750);
FORCEPROP 1 LAST TOLERANCE 20%
J 0
(-2975 2700);
DISPLAY 0.510638 (-2975 2700);
FORCEPROP 1 LAST PACK_TYPE 0201
J 0
(-2975 2600);
DISPLAY 0.510638 (-2975 2600);
FORCEPROP 1 LAST MATERIAL X6S
J 0
(-2975 2650);
DISPLAY 0.510638 (-2975 2650);
FORCEPROP 2 LAST CDS_LIB pure_quanta
J 0
(-3025 2750);
DISPLAY INVISIBLE (-3025 2750);
FORCEPROP 1 LAST PATH I43
J 0
(-2975 2900);
DISPLAY 0.978723 (-2975 2900);
PAINT WHITE (-2975 2900);
DISPLAY INVISIBLE (-2975 2900);
FORCEPROP 1 LAST PART_NUMBER CH-10KMEE00
J 0
(-2975 2600);
DISPLAY 0.510638 (-2975 2600);
DISPLAY INVISIBLE (-2975 2600);
FORCEADD Q_CAP..1
(-3275 3375);
FORCEPROP 1 LAST LOCATION C321
J 0
(-3225 3475);
DISPLAY 0.978723 (-3225 3475);
PAINT WHITE (-3225 3475);
FORCEPROP 0 LAST $SEC 1
J 0
(-3225 3525);
DISPLAY 0.680851 (-3225 3525);
PAINT MONO (-3225 3525);
DISPLAY INVISIBLE (-3225 3525);
FORCEPROP 0 LAST CDS_SEC 1
J 0
(-3225 3525);
DISPLAY 0.680851 (-3225 3525);
DISPLAY INVISIBLE (-3225 3525);
FORCEPROP 1 LASTPIN (-3275 3475) $PN 1
J 0
(-3265 3455);
DISPLAY 0.787234 (-3265 3455);
PAINT MONO (-3265 3455);
FORCEPROP 1 LASTPIN (-3275 3275) $PN 2
J 0
(-3265 3255);
DISPLAY 0.787234 (-3265 3255);
PAINT MONO (-3265 3255);
FORCEPROP 1 LAST MATERIAL X6S
J 0
(-3225 3275);
DISPLAY 0.510638 (-3225 3275);
FORCEPROP 1 LAST VALUE 10UF
J 0
(-3225 3425);
DISPLAY 0.510638 (-3225 3425);
FORCEPROP 1 LAST PACK_TYPE C0402
J 0
(-3225 3225);
DISPLAY 0.510638 (-3225 3225);
FORCEPROP 1 LAST TOLERANCE 20%
J 0
(-3225 3325);
DISPLAY 0.510638 (-3225 3325);
FORCEPROP 1 LAST VOLTAGE 6.3V
J 0
(-3225 3375);
DISPLAY 0.510638 (-3225 3375);
FORCEPROP 2 LAST CDS_LIB pure_quanta
J 0
(-3275 3375);
DISPLAY INVISIBLE (-3275 3375);
FORCEPROP 1 LAST PATH I44
J 0
(-3225 3525);
DISPLAY 0.978723 (-3225 3525);
PAINT WHITE (-3225 3525);
DISPLAY INVISIBLE (-3225 3525);
FORCEPROP 1 LAST PART_NUMBER CH6101MEB01
J 0
(-3225 3225);
DISPLAY 0.978723 (-3225 3225);
DISPLAY INVISIBLE (-3225 3225);
FORCEADD Q_CAP..1
(-3050 3375);
FORCEPROP 1 LAST LOCATION C325
J 0
(-3000 3475);
DISPLAY 0.978723 (-3000 3475);
PAINT WHITE (-3000 3475);
FORCEPROP 0 LAST $SEC 1
J 0
(-3000 3525);
DISPLAY 0.680851 (-3000 3525);
PAINT MONO (-3000 3525);
DISPLAY INVISIBLE (-3000 3525);
FORCEPROP 0 LAST CDS_SEC 1
J 0
(-3000 3525);
DISPLAY 0.680851 (-3000 3525);
DISPLAY INVISIBLE (-3000 3525);
FORCEPROP 1 LASTPIN (-3050 3475) $PN 1
J 0
(-3040 3455);
DISPLAY 0.787234 (-3040 3455);
PAINT MONO (-3040 3455);
FORCEPROP 1 LASTPIN (-3050 3275) $PN 2
J 0
(-3040 3255);
DISPLAY 0.787234 (-3040 3255);
PAINT MONO (-3040 3255);
FORCEPROP 1 LAST VOLTAGE 6.3V
J 0
(-3000 3375);
DISPLAY 0.510638 (-3000 3375);
FORCEPROP 1 LAST MATERIAL X6S
J 0
(-3000 3275);
DISPLAY 0.510638 (-3000 3275);
FORCEPROP 1 LAST PACK_TYPE 0402
J 0
(-3000 3225);
DISPLAY 0.510638 (-3000 3225);
FORCEPROP 1 LAST VALUE 4.7UF
J 0
(-3000 3425);
DISPLAY 0.510638 (-3000 3425);
FORCEPROP 1 LAST TOLERANCE 20%
J 0
(-3000 3325);
DISPLAY 0.510638 (-3000 3325);
FORCEPROP 2 LAST CDS_LIB pure_quanta
J 0
(-3050 3375);
DISPLAY INVISIBLE (-3050 3375);
FORCEPROP 1 LAST PATH I45
J 0
(-3000 3525);
DISPLAY 0.978723 (-3000 3525);
PAINT WHITE (-3000 3525);
DISPLAY INVISIBLE (-3000 3525);
FORCEPROP 1 LAST PART_NUMBER CH5471MEB01
J 0
(-3000 3225);
DISPLAY 0.978723 (-3000 3225);
DISPLAY INVISIBLE (-3000 3225);
FORCEADD Q_CAP..1
(-2825 3375);
FORCEPROP 1 LAST LOCATION C331
J 0
(-2775 3475);
DISPLAY 0.978723 (-2775 3475);
PAINT WHITE (-2775 3475);
FORCEPROP 0 LAST $SEC 1
J 0
(-2775 3525);
DISPLAY 0.680851 (-2775 3525);
PAINT MONO (-2775 3525);
DISPLAY INVISIBLE (-2775 3525);
FORCEPROP 0 LAST CDS_SEC 1
J 0
(-2775 3525);
DISPLAY 0.680851 (-2775 3525);
DISPLAY INVISIBLE (-2775 3525);
FORCEPROP 1 LASTPIN (-2825 3475) $PN 1
J 0
(-2815 3455);
DISPLAY 0.787234 (-2815 3455);
PAINT MONO (-2815 3455);
FORCEPROP 1 LASTPIN (-2825 3275) $PN 2
J 0
(-2815 3255);
DISPLAY 0.787234 (-2815 3255);
PAINT MONO (-2815 3255);
FORCEPROP 1 LAST TOLERANCE 20%
J 0
(-2775 3325);
DISPLAY 0.510638 (-2775 3325);
FORCEPROP 1 LAST VOLTAGE 6.3V
J 0
(-2775 3375);
DISPLAY 0.510638 (-2775 3375);
FORCEPROP 1 LAST MATERIAL X6S
J 0
(-2775 3275);
DISPLAY 0.510638 (-2775 3275);
FORCEPROP 1 LAST VALUE 4.7UF
J 0
(-2775 3425);
DISPLAY 0.510638 (-2775 3425);
FORCEPROP 1 LAST PACK_TYPE 0402
J 0
(-2775 3225);
DISPLAY 0.510638 (-2775 3225);
FORCEPROP 2 LAST CDS_LIB pure_quanta
J 0
(-2825 3375);
DISPLAY INVISIBLE (-2825 3375);
FORCEPROP 1 LAST PATH I46
J 0
(-2775 3525);
DISPLAY 0.978723 (-2775 3525);
PAINT WHITE (-2775 3525);
DISPLAY INVISIBLE (-2775 3525);
FORCEPROP 1 LAST PART_NUMBER CH5471MEB01
J 0
(-2775 3225);
DISPLAY 0.978723 (-2775 3225);
DISPLAY INVISIBLE (-2775 3225);
FORCEADD Q_CAP..1
(-2800 2750);
FORCEPROP 1 LAST LOCATION C330
J 0
(-2750 2850);
DISPLAY 0.978723 (-2750 2850);
PAINT WHITE (-2750 2850);
FORCEPROP 0 LAST $SEC 1
J 0
(-2750 2900);
DISPLAY 0.680851 (-2750 2900);
PAINT MONO (-2750 2900);
DISPLAY INVISIBLE (-2750 2900);
FORCEPROP 0 LAST CDS_SEC 1
J 0
(-2750 2900);
DISPLAY 0.680851 (-2750 2900);
DISPLAY INVISIBLE (-2750 2900);
FORCEPROP 1 LASTPIN (-2800 2850) $PN 1
J 0
(-2790 2830);
DISPLAY 0.787234 (-2790 2830);
PAINT MONO (-2790 2830);
FORCEPROP 1 LASTPIN (-2800 2650) $PN 2
J 0
(-2790 2630);
DISPLAY 0.787234 (-2790 2630);
PAINT MONO (-2790 2630);
FORCEPROP 1 LAST PACK_TYPE 0201
J 0
(-2750 2600);
DISPLAY 0.510638 (-2750 2600);
FORCEPROP 1 LAST MATERIAL X6S
J 0
(-2750 2650);
DISPLAY 0.510638 (-2750 2650);
FORCEPROP 1 LAST VALUE 1UF
J 0
(-2750 2800);
DISPLAY 0.510638 (-2750 2800);
FORCEPROP 1 LAST VOLTAGE 4V
J 0
(-2750 2750);
DISPLAY 0.510638 (-2750 2750);
FORCEPROP 1 LAST TOLERANCE 20%
J 0
(-2750 2700);
DISPLAY 0.510638 (-2750 2700);
FORCEPROP 2 LAST CDS_LIB pure_quanta
J 0
(-2800 2750);
DISPLAY INVISIBLE (-2800 2750);
FORCEPROP 1 LAST PATH I47
J 0
(-2750 2900);
DISPLAY 0.978723 (-2750 2900);
PAINT WHITE (-2750 2900);
DISPLAY INVISIBLE (-2750 2900);
FORCEPROP 1 LAST PART_NUMBER CH-10KMEE00
J 0
(-2750 2600);
DISPLAY 0.510638 (-2750 2600);
DISPLAY INVISIBLE (-2750 2600);
FORCEADD Q_CAP..1
(-2700 2050);
FORCEPROP 1 LAST LOCATION C312
J 0
(-2650 2150);
DISPLAY 0.978723 (-2650 2150);
PAINT WHITE (-2650 2150);
FORCEPROP 0 LAST $SEC 1
J 0
(-2650 2200);
DISPLAY 0.680851 (-2650 2200);
PAINT MONO (-2650 2200);
DISPLAY INVISIBLE (-2650 2200);
FORCEPROP 0 LAST CDS_SEC 1
J 0
(-2650 2200);
DISPLAY 0.680851 (-2650 2200);
DISPLAY INVISIBLE (-2650 2200);
FORCEPROP 1 LASTPIN (-2700 2150) $PN 1
J 0
(-2690 2130);
DISPLAY 0.787234 (-2690 2130);
PAINT MONO (-2690 2130);
FORCEPROP 1 LASTPIN (-2700 1950) $PN 2
J 0
(-2690 1930);
DISPLAY 0.787234 (-2690 1930);
PAINT MONO (-2690 1930);
FORCEPROP 1 LAST VALUE 0.1UF
J 0
(-2650 2100);
DISPLAY 0.638298 (-2650 2100);
FORCEPROP 1 LAST VOLTAGE 10V
J 0
(-2650 2050);
DISPLAY 0.638298 (-2650 2050);
FORCEPROP 1 LAST PACK_TYPE C0201
J 0
(-2650 1900);
DISPLAY 0.638298 (-2650 1900);
FORCEPROP 1 LAST MATERIAL X7S
J 0
(-2650 1950);
DISPLAY 0.638298 (-2650 1950);
FORCEPROP 1 LAST TOLERANCE 10%
J 0
(-2650 2000);
DISPLAY 0.638298 (-2650 2000);
FORCEPROP 2 LAST CDS_LIB pure_quanta
J 0
(-2700 2050);
DISPLAY INVISIBLE (-2700 2050);
FORCEPROP 1 LAST PATH I48
J 0
(-2650 2200);
DISPLAY 0.978723 (-2650 2200);
PAINT WHITE (-2650 2200);
DISPLAY INVISIBLE (-2650 2200);
FORCEPROP 1 LAST PART_NUMBER CH4102K6E00
J 0
(-2650 1900);
DISPLAY 0.978723 (-2650 1900);
DISPLAY INVISIBLE (-2650 1900);
FORCEADD Q_CAP..1
(-2450 2050);
FORCEPROP 1 LAST LOCATION C349
J 0
(-2400 2150);
DISPLAY 0.978723 (-2400 2150);
PAINT WHITE (-2400 2150);
FORCEPROP 0 LAST $SEC 1
J 0
(-2400 2200);
DISPLAY 0.680851 (-2400 2200);
PAINT MONO (-2400 2200);
DISPLAY INVISIBLE (-2400 2200);
FORCEPROP 0 LAST CDS_SEC 1
J 0
(-2400 2200);
DISPLAY 0.680851 (-2400 2200);
DISPLAY INVISIBLE (-2400 2200);
FORCEPROP 1 LASTPIN (-2450 2150) $PN 1
J 0
(-2440 2130);
DISPLAY 0.787234 (-2440 2130);
PAINT MONO (-2440 2130);
FORCEPROP 1 LASTPIN (-2450 1950) $PN 2
J 0
(-2440 1930);
DISPLAY 0.787234 (-2440 1930);
PAINT MONO (-2440 1930);
FORCEPROP 1 LAST VALUE 0.1UF
J 0
(-2400 2100);
DISPLAY 0.638298 (-2400 2100);
FORCEPROP 1 LAST VOLTAGE 10V
J 0
(-2400 2050);
DISPLAY 0.638298 (-2400 2050);
FORCEPROP 1 LAST PACK_TYPE C0201
J 0
(-2400 1900);
DISPLAY 0.638298 (-2400 1900);
FORCEPROP 1 LAST MATERIAL X7S
J 0
(-2400 1950);
DISPLAY 0.638298 (-2400 1950);
FORCEPROP 1 LAST TOLERANCE 10%
J 0
(-2400 2000);
DISPLAY 0.638298 (-2400 2000);
FORCEPROP 2 LAST CDS_LIB pure_quanta
J 0
(-2450 2050);
DISPLAY INVISIBLE (-2450 2050);
FORCEPROP 1 LAST PATH I49
J 0
(-2400 2200);
DISPLAY 0.978723 (-2400 2200);
PAINT WHITE (-2400 2200);
DISPLAY INVISIBLE (-2400 2200);
FORCEPROP 1 LAST PART_NUMBER CH4102K6E00
J 0
(-2400 1900);
DISPLAY 0.978723 (-2400 1900);
DISPLAY INVISIBLE (-2400 1900);
FORCEADD Q_RES..1
(-7725 3575);
FORCEPROP 1 LAST LOCATION R653
J 0
(-8000 3600);
DISPLAY 0.808511 (-8000 3600);
FORCEPROP 2 LAST SEC 1
J 0
(-7775 3775);
DISPLAY 0.680851 (-7775 3775);
PAINT MONO (-7775 3775);
DISPLAY INVISIBLE (-7775 3775);
FORCEPROP 1 LASTPIN (-7825 3575) $PN 1
J 0
(-7813 3587);
DISPLAY 0.787234 (-7813 3587);
PAINT MONO (-7813 3587);
FORCEPROP 1 LASTPIN (-7625 3575) $PN 2
J 0
(-7663 3587);
DISPLAY 0.787234 (-7663 3587);
PAINT MONO (-7663 3587);
FORCEPROP 1 LAST MATERIAL EMPTY
J 0
(-7700 3475);
DISPLAY 0.638298 (-7700 3475);
FORCEPROP 1 LAST WATTAGE 1/16W
J 2
(-7725 3475);
DISPLAY 0.638298 (-7725 3475);
FORCEPROP 1 LAST PACK_TYPE 0402LF
J 0
(-7875 3525);
DISPLAY 0.638298 (-7875 3525);
FORCEPROP 1 LAST TOLERANCE 5%
J 0
(-7675 3525);
DISPLAY 0.638298 (-7675 3525);
FORCEPROP 1 LAST VALUE 0
J 2
(-7575 3600);
DISPLAY 0.638298 (-7575 3600);
FORCEPROP 2 LAST SEC_TYPE 0402LF
J 0
(-7775 3775);
DISPLAY 0.680851 (-7775 3775);
DISPLAY INVISIBLE (-7775 3775);
FORCEPROP 2 LAST CDS_LIB pure_quanta
J 0
(-7725 3575);
DISPLAY INVISIBLE (-7725 3575);
FORCEPROP 1 LAST PATH I5
J 0
(-7775 3725);
DISPLAY 0.978723 (-7775 3725);
PAINT WHITE (-7775 3725);
DISPLAY INVISIBLE (-7775 3725);
FORCEPROP 1 LAST PART_NUMBER CS00002JB13
J 0
(-7775 3675);
DISPLAY 0.978723 (-7775 3675);
DISPLAY INVISIBLE (-7775 3675);
FORCEADD Q_CAP..1
(-2200 2050);
FORCEPROP 1 LAST LOCATION C291
J 0
(-2150 2150);
DISPLAY 0.978723 (-2150 2150);
PAINT WHITE (-2150 2150);
FORCEPROP 0 LAST $SEC 1
J 0
(-2150 2200);
DISPLAY 0.680851 (-2150 2200);
PAINT MONO (-2150 2200);
DISPLAY INVISIBLE (-2150 2200);
FORCEPROP 0 LAST CDS_SEC 1
J 0
(-2150 2200);
DISPLAY 0.680851 (-2150 2200);
DISPLAY INVISIBLE (-2150 2200);
FORCEPROP 1 LASTPIN (-2200 2150) $PN 1
J 0
(-2190 2130);
DISPLAY 0.787234 (-2190 2130);
PAINT MONO (-2190 2130);
FORCEPROP 1 LASTPIN (-2200 1950) $PN 2
J 0
(-2190 1930);
DISPLAY 0.787234 (-2190 1930);
PAINT MONO (-2190 1930);
FORCEPROP 1 LAST PACK_TYPE C0201
J 0
(-2150 1900);
DISPLAY 0.638298 (-2150 1900);
FORCEPROP 1 LAST MATERIAL X7S
J 0
(-2150 1950);
DISPLAY 0.638298 (-2150 1950);
FORCEPROP 1 LAST TOLERANCE 10%
J 0
(-2150 2000);
DISPLAY 0.638298 (-2150 2000);
FORCEPROP 1 LAST VOLTAGE 10V
J 0
(-2150 2050);
DISPLAY 0.638298 (-2150 2050);
FORCEPROP 1 LAST VALUE 0.1UF
J 0
(-2150 2100);
DISPLAY 0.638298 (-2150 2100);
FORCEPROP 2 LAST CDS_LIB pure_quanta
J 0
(-2200 2050);
DISPLAY INVISIBLE (-2200 2050);
FORCEPROP 1 LAST PATH I50
J 0
(-2150 2200);
DISPLAY 0.978723 (-2150 2200);
PAINT WHITE (-2150 2200);
DISPLAY INVISIBLE (-2150 2200);
FORCEPROP 1 LAST PART_NUMBER CH4102K6E00
J 0
(-2150 1900);
DISPLAY 0.978723 (-2150 1900);
DISPLAY INVISIBLE (-2150 1900);
FORCEADD Q_CAP..1
(-1925 2050);
FORCEPROP 1 LAST LOCATION C319
J 0
(-1875 2150);
DISPLAY 0.978723 (-1875 2150);
PAINT WHITE (-1875 2150);
FORCEPROP 0 LAST $SEC 1
J 0
(-1875 2200);
DISPLAY 0.680851 (-1875 2200);
PAINT MONO (-1875 2200);
DISPLAY INVISIBLE (-1875 2200);
FORCEPROP 0 LAST CDS_SEC 1
J 0
(-1875 2200);
DISPLAY 0.680851 (-1875 2200);
DISPLAY INVISIBLE (-1875 2200);
FORCEPROP 1 LASTPIN (-1925 2150) $PN 1
J 0
(-1915 2130);
DISPLAY 0.787234 (-1915 2130);
PAINT MONO (-1915 2130);
FORCEPROP 1 LASTPIN (-1925 1950) $PN 2
J 0
(-1915 1930);
DISPLAY 0.787234 (-1915 1930);
PAINT MONO (-1915 1930);
FORCEPROP 1 LAST PACK_TYPE C0201
J 0
(-1875 1900);
DISPLAY 0.638298 (-1875 1900);
FORCEPROP 1 LAST VOLTAGE 10V
J 0
(-1875 2050);
DISPLAY 0.638298 (-1875 2050);
FORCEPROP 1 LAST VALUE 0.1UF
J 0
(-1875 2100);
DISPLAY 0.638298 (-1875 2100);
FORCEPROP 1 LAST TOLERANCE 10%
J 0
(-1875 2000);
DISPLAY 0.638298 (-1875 2000);
FORCEPROP 1 LAST MATERIAL X7S
J 0
(-1875 1950);
DISPLAY 0.638298 (-1875 1950);
FORCEPROP 2 LAST CDS_LIB pure_quanta
J 0
(-1925 2050);
DISPLAY INVISIBLE (-1925 2050);
FORCEPROP 1 LAST PATH I51
J 0
(-1875 2200);
DISPLAY 0.978723 (-1875 2200);
PAINT WHITE (-1875 2200);
DISPLAY INVISIBLE (-1875 2200);
FORCEPROP 1 LAST PART_NUMBER CH4102K6E00
J 0
(-1875 1900);
DISPLAY 0.978723 (-1875 1900);
DISPLAY INVISIBLE (-1875 1900);
FORCEADD Q_CAP..1
(-2550 2750);
FORCEPROP 1 LAST LOCATION C314
J 0
(-2500 2850);
DISPLAY 0.978723 (-2500 2850);
PAINT WHITE (-2500 2850);
FORCEPROP 0 LAST $SEC 1
J 0
(-2500 2900);
DISPLAY 0.680851 (-2500 2900);
PAINT MONO (-2500 2900);
DISPLAY INVISIBLE (-2500 2900);
FORCEPROP 0 LAST CDS_SEC 1
J 0
(-2500 2900);
DISPLAY 0.680851 (-2500 2900);
DISPLAY INVISIBLE (-2500 2900);
FORCEPROP 1 LASTPIN (-2550 2850) $PN 1
J 0
(-2540 2830);
DISPLAY 0.787234 (-2540 2830);
PAINT MONO (-2540 2830);
FORCEPROP 1 LASTPIN (-2550 2650) $PN 2
J 0
(-2540 2630);
DISPLAY 0.787234 (-2540 2630);
PAINT MONO (-2540 2630);
FORCEPROP 1 LAST VALUE 1UF
J 0
(-2500 2800);
DISPLAY 0.510638 (-2500 2800);
FORCEPROP 1 LAST PACK_TYPE 0201
J 0
(-2500 2600);
DISPLAY 0.510638 (-2500 2600);
FORCEPROP 1 LAST TOLERANCE 20%
J 0
(-2500 2700);
DISPLAY 0.510638 (-2500 2700);
FORCEPROP 1 LAST VOLTAGE 4V
J 0
(-2500 2750);
DISPLAY 0.510638 (-2500 2750);
FORCEPROP 1 LAST MATERIAL X6S
J 0
(-2500 2650);
DISPLAY 0.510638 (-2500 2650);
FORCEPROP 2 LAST CDS_LIB pure_quanta
J 0
(-2550 2750);
DISPLAY INVISIBLE (-2550 2750);
FORCEPROP 1 LAST PATH I52
J 0
(-2500 2900);
DISPLAY 0.978723 (-2500 2900);
PAINT WHITE (-2500 2900);
DISPLAY INVISIBLE (-2500 2900);
FORCEPROP 1 LAST PART_NUMBER CH-10KMEE00
J 0
(-2500 2600);
DISPLAY 0.510638 (-2500 2600);
DISPLAY INVISIBLE (-2500 2600);
FORCEADD Q_CAP..1
(-2325 2725);
FORCEPROP 1 LAST LOCATION C337
J 0
(-2275 2825);
DISPLAY 0.978723 (-2275 2825);
PAINT WHITE (-2275 2825);
FORCEPROP 0 LAST $SEC 1
J 0
(-2275 2875);
DISPLAY 0.680851 (-2275 2875);
PAINT MONO (-2275 2875);
DISPLAY INVISIBLE (-2275 2875);
FORCEPROP 0 LAST CDS_SEC 1
J 0
(-2275 2875);
DISPLAY 0.680851 (-2275 2875);
DISPLAY INVISIBLE (-2275 2875);
FORCEPROP 1 LASTPIN (-2325 2825) $PN 1
J 0
(-2315 2805);
DISPLAY 0.787234 (-2315 2805);
PAINT MONO (-2315 2805);
FORCEPROP 1 LASTPIN (-2325 2625) $PN 2
J 0
(-2315 2605);
DISPLAY 0.787234 (-2315 2605);
PAINT MONO (-2315 2605);
FORCEPROP 1 LAST PACK_TYPE 0201
J 0
(-2275 2575);
DISPLAY 0.510638 (-2275 2575);
FORCEPROP 1 LAST VOLTAGE 4V
J 0
(-2275 2725);
DISPLAY 0.510638 (-2275 2725);
FORCEPROP 1 LAST MATERIAL X6S
J 0
(-2275 2625);
DISPLAY 0.510638 (-2275 2625);
FORCEPROP 1 LAST TOLERANCE 20%
J 0
(-2275 2675);
DISPLAY 0.510638 (-2275 2675);
FORCEPROP 1 LAST VALUE 1UF
J 0
(-2275 2775);
DISPLAY 0.510638 (-2275 2775);
FORCEPROP 2 LAST CDS_LIB pure_quanta
J 0
(-2325 2725);
DISPLAY INVISIBLE (-2325 2725);
FORCEPROP 1 LAST PATH I53
J 0
(-2275 2875);
DISPLAY 0.978723 (-2275 2875);
PAINT WHITE (-2275 2875);
DISPLAY INVISIBLE (-2275 2875);
FORCEPROP 1 LAST PART_NUMBER CH-10KMEE00
J 0
(-2275 2575);
DISPLAY 0.510638 (-2275 2575);
DISPLAY INVISIBLE (-2275 2575);
FORCEADD Q_CAP..1
(-2575 3375);
FORCEPROP 1 LAST LOCATION C343
J 0
(-2525 3475);
DISPLAY 0.978723 (-2525 3475);
PAINT WHITE (-2525 3475);
FORCEPROP 0 LAST $SEC 1
J 0
(-2525 3525);
DISPLAY 0.680851 (-2525 3525);
PAINT MONO (-2525 3525);
DISPLAY INVISIBLE (-2525 3525);
FORCEPROP 0 LAST CDS_SEC 1
J 0
(-2525 3525);
DISPLAY 0.680851 (-2525 3525);
DISPLAY INVISIBLE (-2525 3525);
FORCEPROP 1 LASTPIN (-2575 3475) $PN 1
J 0
(-2565 3455);
DISPLAY 0.787234 (-2565 3455);
PAINT MONO (-2565 3455);
FORCEPROP 1 LASTPIN (-2575 3275) $PN 2
J 0
(-2565 3255);
DISPLAY 0.787234 (-2565 3255);
PAINT MONO (-2565 3255);
FORCEPROP 1 LAST MATERIAL X6S
J 0
(-2525 3275);
DISPLAY 0.510638 (-2525 3275);
FORCEPROP 1 LAST VALUE 4.7UF
J 0
(-2525 3425);
DISPLAY 0.510638 (-2525 3425);
FORCEPROP 1 LAST PACK_TYPE 0402
J 0
(-2525 3225);
DISPLAY 0.510638 (-2525 3225);
FORCEPROP 1 LAST VOLTAGE 6.3V
J 0
(-2525 3375);
DISPLAY 0.510638 (-2525 3375);
FORCEPROP 1 LAST TOLERANCE 20%
J 0
(-2525 3325);
DISPLAY 0.510638 (-2525 3325);
FORCEPROP 2 LAST CDS_LIB pure_quanta
J 0
(-2575 3375);
DISPLAY INVISIBLE (-2575 3375);
FORCEPROP 1 LAST PATH I54
J 0
(-2525 3525);
DISPLAY 0.978723 (-2525 3525);
PAINT WHITE (-2525 3525);
DISPLAY INVISIBLE (-2525 3525);
FORCEPROP 1 LAST PART_NUMBER CH5471MEB01
J 0
(-2525 3225);
DISPLAY 0.978723 (-2525 3225);
DISPLAY INVISIBLE (-2525 3225);
FORCEADD Q_CAP..1
(-2350 3375);
FORCEPROP 1 LAST LOCATION C336
J 0
(-2300 3475);
DISPLAY 0.978723 (-2300 3475);
PAINT WHITE (-2300 3475);
FORCEPROP 0 LAST $SEC 1
J 0
(-2300 3525);
DISPLAY 0.680851 (-2300 3525);
PAINT MONO (-2300 3525);
DISPLAY INVISIBLE (-2300 3525);
FORCEPROP 0 LAST CDS_SEC 1
J 0
(-2300 3525);
DISPLAY 0.680851 (-2300 3525);
DISPLAY INVISIBLE (-2300 3525);
FORCEPROP 1 LASTPIN (-2350 3475) $PN 1
J 0
(-2340 3455);
DISPLAY 0.787234 (-2340 3455);
PAINT MONO (-2340 3455);
FORCEPROP 1 LASTPIN (-2350 3275) $PN 2
J 0
(-2340 3255);
DISPLAY 0.787234 (-2340 3255);
PAINT MONO (-2340 3255);
FORCEPROP 1 LAST TOLERANCE 20%
J 0
(-2300 3325);
DISPLAY 0.510638 (-2300 3325);
FORCEPROP 1 LAST PACK_TYPE 0402
J 0
(-2300 3225);
DISPLAY 0.510638 (-2300 3225);
FORCEPROP 1 LAST MATERIAL X6S
J 0
(-2300 3275);
DISPLAY 0.510638 (-2300 3275);
FORCEPROP 1 LAST VALUE 4.7UF
J 0
(-2300 3425);
DISPLAY 0.510638 (-2300 3425);
FORCEPROP 1 LAST VOLTAGE 6.3V
J 0
(-2300 3375);
DISPLAY 0.510638 (-2300 3375);
FORCEPROP 2 LAST CDS_LIB pure_quanta
J 0
(-2350 3375);
DISPLAY INVISIBLE (-2350 3375);
FORCEPROP 1 LAST PATH I55
J 0
(-2300 3525);
DISPLAY 0.978723 (-2300 3525);
PAINT WHITE (-2300 3525);
DISPLAY INVISIBLE (-2300 3525);
FORCEPROP 1 LAST PART_NUMBER CH5471MEB01
J 0
(-2300 3225);
DISPLAY 0.978723 (-2300 3225);
DISPLAY INVISIBLE (-2300 3225);
FORCEADD Q_CAP..1
(-2075 2725);
FORCEPROP 1 LAST LOCATION C346
J 0
(-2025 2825);
DISPLAY 0.978723 (-2025 2825);
PAINT WHITE (-2025 2825);
FORCEPROP 0 LAST $SEC 1
J 0
(-2025 2875);
DISPLAY 0.680851 (-2025 2875);
PAINT MONO (-2025 2875);
DISPLAY INVISIBLE (-2025 2875);
FORCEPROP 0 LAST CDS_SEC 1
J 0
(-2025 2875);
DISPLAY 0.680851 (-2025 2875);
DISPLAY INVISIBLE (-2025 2875);
FORCEPROP 1 LASTPIN (-2075 2825) $PN 1
J 0
(-2065 2805);
DISPLAY 0.787234 (-2065 2805);
PAINT MONO (-2065 2805);
FORCEPROP 1 LASTPIN (-2075 2625) $PN 2
J 0
(-2065 2605);
DISPLAY 0.787234 (-2065 2605);
PAINT MONO (-2065 2605);
FORCEPROP 1 LAST MATERIAL X6S
J 0
(-2025 2625);
DISPLAY 0.510638 (-2025 2625);
FORCEPROP 1 LAST PACK_TYPE 0201
J 0
(-2025 2575);
DISPLAY 0.510638 (-2025 2575);
FORCEPROP 1 LAST VALUE 1UF
J 0
(-2025 2775);
DISPLAY 0.510638 (-2025 2775);
FORCEPROP 1 LAST VOLTAGE 4V
J 0
(-2025 2725);
DISPLAY 0.510638 (-2025 2725);
FORCEPROP 1 LAST TOLERANCE 20%
J 0
(-2025 2675);
DISPLAY 0.510638 (-2025 2675);
FORCEPROP 2 LAST CDS_LIB pure_quanta
J 0
(-2075 2725);
DISPLAY INVISIBLE (-2075 2725);
FORCEPROP 1 LAST PATH I57
J 0
(-2025 2875);
DISPLAY 0.978723 (-2025 2875);
PAINT WHITE (-2025 2875);
DISPLAY INVISIBLE (-2025 2875);
FORCEPROP 1 LAST PART_NUMBER CH-10KMEE00
J 0
(-2025 2575);
DISPLAY 0.510638 (-2025 2575);
DISPLAY INVISIBLE (-2025 2575);
FORCEADD Q_CAP..1
(-2125 3375);
FORCEPROP 1 LAST LOCATION C293
J 0
(-2075 3475);
DISPLAY 0.978723 (-2075 3475);
PAINT WHITE (-2075 3475);
FORCEPROP 0 LAST $SEC 1
J 0
(-2075 3525);
DISPLAY 0.680851 (-2075 3525);
PAINT MONO (-2075 3525);
DISPLAY INVISIBLE (-2075 3525);
FORCEPROP 0 LAST CDS_SEC 1
J 0
(-2075 3525);
DISPLAY 0.680851 (-2075 3525);
DISPLAY INVISIBLE (-2075 3525);
FORCEPROP 1 LASTPIN (-2125 3475) $PN 1
J 0
(-2115 3455);
DISPLAY 0.787234 (-2115 3455);
PAINT MONO (-2115 3455);
FORCEPROP 1 LASTPIN (-2125 3275) $PN 2
J 0
(-2115 3255);
DISPLAY 0.787234 (-2115 3255);
PAINT MONO (-2115 3255);
FORCEPROP 1 LAST MATERIAL X6S
J 0
(-2075 3275);
DISPLAY 0.510638 (-2075 3275);
FORCEPROP 1 LAST TOLERANCE 20%
J 0
(-2075 3325);
DISPLAY 0.510638 (-2075 3325);
FORCEPROP 1 LAST VALUE 1UF
J 0
(-2075 3425);
DISPLAY 0.510638 (-2075 3425);
FORCEPROP 1 LAST VOLTAGE 4V
J 0
(-2075 3375);
DISPLAY 0.510638 (-2075 3375);
FORCEPROP 1 LAST PACK_TYPE 0201
J 0
(-2075 3225);
DISPLAY 0.510638 (-2075 3225);
FORCEPROP 2 LAST CDS_LIB pure_quanta
J 0
(-2125 3375);
DISPLAY INVISIBLE (-2125 3375);
FORCEPROP 1 LAST PATH I58
J 0
(-2075 3525);
DISPLAY 0.978723 (-2075 3525);
PAINT WHITE (-2075 3525);
DISPLAY INVISIBLE (-2075 3525);
FORCEPROP 1 LAST PART_NUMBER CH-10KMEE00
J 0
(-2075 3225);
DISPLAY 0.510638 (-2075 3225);
DISPLAY INVISIBLE (-2075 3225);
FORCEADD Q_CAP..1
(-1900 3375);
FORCEPROP 1 LAST LOCATION C301
J 0
(-1850 3475);
DISPLAY 0.978723 (-1850 3475);
PAINT WHITE (-1850 3475);
FORCEPROP 0 LAST $SEC 1
J 0
(-1850 3525);
DISPLAY 0.680851 (-1850 3525);
PAINT MONO (-1850 3525);
DISPLAY INVISIBLE (-1850 3525);
FORCEPROP 0 LAST CDS_SEC 1
J 0
(-1850 3525);
DISPLAY 0.680851 (-1850 3525);
DISPLAY INVISIBLE (-1850 3525);
FORCEPROP 1 LASTPIN (-1900 3475) $PN 1
J 0
(-1890 3455);
DISPLAY 0.787234 (-1890 3455);
PAINT MONO (-1890 3455);
FORCEPROP 1 LASTPIN (-1900 3275) $PN 2
J 0
(-1890 3255);
DISPLAY 0.787234 (-1890 3255);
PAINT MONO (-1890 3255);
FORCEPROP 1 LAST PACK_TYPE 0201
J 0
(-1850 3225);
DISPLAY 0.510638 (-1850 3225);
FORCEPROP 1 LAST MATERIAL X6S
J 0
(-1850 3275);
DISPLAY 0.510638 (-1850 3275);
FORCEPROP 1 LAST TOLERANCE 20%
J 0
(-1850 3325);
DISPLAY 0.510638 (-1850 3325);
FORCEPROP 1 LAST VOLTAGE 4V
J 0
(-1850 3375);
DISPLAY 0.510638 (-1850 3375);
FORCEPROP 1 LAST VALUE 1UF
J 0
(-1850 3425);
DISPLAY 0.510638 (-1850 3425);
FORCEPROP 2 LAST CDS_LIB pure_quanta
J 0
(-1900 3375);
DISPLAY INVISIBLE (-1900 3375);
FORCEPROP 1 LAST PATH I59
J 0
(-1850 3525);
DISPLAY 0.978723 (-1850 3525);
PAINT WHITE (-1850 3525);
DISPLAY INVISIBLE (-1850 3525);
FORCEPROP 1 LAST PART_NUMBER CH-10KMEE00
J 0
(-1850 3225);
DISPLAY 0.510638 (-1850 3225);
DISPLAY INVISIBLE (-1850 3225);
FORCEADD P1V0..1
(-6925 3300);
FORCEPROP 3 LASTPIN (-6925 3250) SIG_NAME P1V8_CPU1_RT1_1A_1D\g
J 0
(-6915 3260);
DISPLAY 0.659574 (-6915 3260);
PAINT MONO (-6915 3260);
DISPLAY INVISIBLE (-6915 3260);
FORCEPROP 1 LAST HDL_POWER P1V8_CPU1_RT1_1A_1D
J 1
(-6925 3350);
DISPLAY 0.489362 (-6925 3350);
PAINT SKYBLUE (-6925 3350);
FORCEPROP 2 LAST CDS_LIB pure_quanta_power
J 0
(-6925 3300);
DISPLAY INVISIBLE (-6925 3300);
FORCEPROP 1 LAST PATH I6
J 0
(-6875 3325);
DISPLAY 0.872340 (-6875 3325);
PAINT AQUA (-6875 3325);
DISPLAY INVISIBLE (-6875 3325);
FORCEADD Q_CAP..1
(-1650 2050);
FORCEPROP 1 LAST LOCATION C322
J 0
(-1600 2150);
DISPLAY 0.978723 (-1600 2150);
PAINT WHITE (-1600 2150);
FORCEPROP 0 LAST $SEC 1
J 0
(-1600 2200);
DISPLAY 0.680851 (-1600 2200);
PAINT MONO (-1600 2200);
DISPLAY INVISIBLE (-1600 2200);
FORCEPROP 0 LAST CDS_SEC 1
J 0
(-1600 2200);
DISPLAY 0.680851 (-1600 2200);
DISPLAY INVISIBLE (-1600 2200);
FORCEPROP 1 LASTPIN (-1650 2150) $PN 1
J 0
(-1640 2130);
DISPLAY 0.787234 (-1640 2130);
PAINT MONO (-1640 2130);
FORCEPROP 1 LASTPIN (-1650 1950) $PN 2
J 0
(-1640 1930);
DISPLAY 0.787234 (-1640 1930);
PAINT MONO (-1640 1930);
FORCEPROP 1 LAST PACK_TYPE C0201
J 0
(-1600 1900);
DISPLAY 0.638298 (-1600 1900);
FORCEPROP 1 LAST VALUE 0.1UF
J 0
(-1600 2100);
DISPLAY 0.638298 (-1600 2100);
FORCEPROP 1 LAST VOLTAGE 10V
J 0
(-1600 2050);
DISPLAY 0.638298 (-1600 2050);
FORCEPROP 1 LAST TOLERANCE 10%
J 0
(-1600 2000);
DISPLAY 0.638298 (-1600 2000);
FORCEPROP 1 LAST MATERIAL X7S
J 0
(-1600 1950);
DISPLAY 0.638298 (-1600 1950);
FORCEPROP 2 LAST CDS_LIB pure_quanta
J 0
(-1650 2050);
DISPLAY INVISIBLE (-1650 2050);
FORCEPROP 1 LAST PATH I60
J 0
(-1600 2200);
DISPLAY 0.978723 (-1600 2200);
PAINT WHITE (-1600 2200);
DISPLAY INVISIBLE (-1600 2200);
FORCEPROP 1 LAST PART_NUMBER CH4102K6E00
J 0
(-1600 1900);
DISPLAY 0.978723 (-1600 1900);
DISPLAY INVISIBLE (-1600 1900);
FORCEADD UNIVERSAL_GND..1
(-1400 1625);
FORCEPROP 3 LASTPIN (-1400 1675) SIG_NAME GND\g
J 0
(-1390 1685);
DISPLAY 0.659574 (-1390 1685);
PAINT MONO (-1390 1685);
DISPLAY INVISIBLE (-1390 1685);
FORCEPROP 2 LAST CDS_LIB pure_quanta_power
J 0
(-1400 1625);
DISPLAY INVISIBLE (-1400 1625);
FORCEPROP 1 LAST HDL_POWER GND
J 1
(-1375 1550);
DISPLAY 0.872340 (-1375 1550);
PAINT GREEN (-1375 1550);
DISPLAY INVISIBLE (-1375 1550);
FORCEPROP 1 LAST PATH I61
J 0
(-1325 1625);
DISPLAY 0.872340 (-1325 1625);
PAINT AQUA (-1325 1625);
DISPLAY INVISIBLE (-1325 1625);
FORCEADD Q_CAP..1
(-1400 2050);
FORCEPROP 1 LAST LOCATION C334
J 0
(-1350 2150);
DISPLAY 0.978723 (-1350 2150);
PAINT WHITE (-1350 2150);
FORCEPROP 0 LAST $SEC 1
J 0
(-1350 2200);
DISPLAY 0.680851 (-1350 2200);
PAINT MONO (-1350 2200);
DISPLAY INVISIBLE (-1350 2200);
FORCEPROP 0 LAST CDS_SEC 1
J 0
(-1350 2200);
DISPLAY 0.680851 (-1350 2200);
DISPLAY INVISIBLE (-1350 2200);
FORCEPROP 1 LASTPIN (-1400 2150) $PN 1
J 0
(-1390 2130);
DISPLAY 0.787234 (-1390 2130);
PAINT MONO (-1390 2130);
FORCEPROP 1 LASTPIN (-1400 1950) $PN 2
J 0
(-1390 1930);
DISPLAY 0.787234 (-1390 1930);
PAINT MONO (-1390 1930);
FORCEPROP 1 LAST PACK_TYPE C0201
J 0
(-1350 1900);
DISPLAY 0.638298 (-1350 1900);
FORCEPROP 1 LAST TOLERANCE 10%
J 0
(-1350 2000);
DISPLAY 0.638298 (-1350 2000);
FORCEPROP 1 LAST VALUE 0.1UF
J 0
(-1350 2100);
DISPLAY 0.638298 (-1350 2100);
FORCEPROP 1 LAST VOLTAGE 10V
J 0
(-1350 2050);
DISPLAY 0.638298 (-1350 2050);
FORCEPROP 1 LAST MATERIAL X7S
J 0
(-1350 1950);
DISPLAY 0.638298 (-1350 1950);
FORCEPROP 2 LAST CDS_LIB pure_quanta
J 0
(-1400 2050);
DISPLAY INVISIBLE (-1400 2050);
FORCEPROP 1 LAST PATH I62
J 0
(-1350 2200);
DISPLAY 0.978723 (-1350 2200);
PAINT WHITE (-1350 2200);
DISPLAY INVISIBLE (-1350 2200);
FORCEPROP 1 LAST PART_NUMBER CH4102K6E00
J 0
(-1350 1900);
DISPLAY 0.978723 (-1350 1900);
DISPLAY INVISIBLE (-1350 1900);
FORCEADD UNIVERSAL_GND..1
(-900 2325);
FORCEPROP 3 LASTPIN (-900 2375) SIG_NAME GND\g
J 0
(-890 2385);
DISPLAY 0.659574 (-890 2385);
PAINT MONO (-890 2385);
DISPLAY INVISIBLE (-890 2385);
FORCEPROP 2 LAST CDS_LIB pure_quanta_power
J 0
(-900 2325);
DISPLAY INVISIBLE (-900 2325);
FORCEPROP 1 LAST HDL_POWER GND
J 1
(-875 2250);
DISPLAY 0.872340 (-875 2250);
PAINT GREEN (-875 2250);
DISPLAY INVISIBLE (-875 2250);
FORCEPROP 1 LAST PATH I63
J 0
(-825 2325);
DISPLAY 0.872340 (-825 2325);
PAINT AQUA (-825 2325);
DISPLAY INVISIBLE (-825 2325);
FORCEADD Q_CAP..1
(-1675 3375);
FORCEPROP 1 LAST LOCATION C289
J 0
(-1625 3475);
DISPLAY 0.978723 (-1625 3475);
PAINT WHITE (-1625 3475);
FORCEPROP 0 LAST $SEC 1
J 0
(-1625 3525);
DISPLAY 0.680851 (-1625 3525);
PAINT MONO (-1625 3525);
DISPLAY INVISIBLE (-1625 3525);
FORCEPROP 0 LAST CDS_SEC 1
J 0
(-1625 3525);
DISPLAY 0.680851 (-1625 3525);
DISPLAY INVISIBLE (-1625 3525);
FORCEPROP 1 LASTPIN (-1675 3475) $PN 1
J 0
(-1665 3455);
DISPLAY 0.787234 (-1665 3455);
PAINT MONO (-1665 3455);
FORCEPROP 1 LASTPIN (-1675 3275) $PN 2
J 0
(-1665 3255);
DISPLAY 0.787234 (-1665 3255);
PAINT MONO (-1665 3255);
FORCEPROP 1 LAST PACK_TYPE 0201
J 0
(-1625 3225);
DISPLAY 0.510638 (-1625 3225);
FORCEPROP 1 LAST TOLERANCE 20%
J 0
(-1625 3325);
DISPLAY 0.510638 (-1625 3325);
FORCEPROP 1 LAST VOLTAGE 4V
J 0
(-1625 3375);
DISPLAY 0.510638 (-1625 3375);
FORCEPROP 1 LAST MATERIAL X6S
J 0
(-1625 3275);
DISPLAY 0.510638 (-1625 3275);
FORCEPROP 1 LAST VALUE 1UF
J 0
(-1625 3425);
DISPLAY 0.510638 (-1625 3425);
FORCEPROP 2 LAST CDS_LIB pure_quanta
J 0
(-1675 3375);
DISPLAY INVISIBLE (-1675 3375);
FORCEPROP 1 LAST PATH I65
J 0
(-1625 3525);
DISPLAY 0.978723 (-1625 3525);
PAINT WHITE (-1625 3525);
DISPLAY INVISIBLE (-1625 3525);
FORCEPROP 1 LAST PART_NUMBER CH-10KMEE00
J 0
(-1625 3225);
DISPLAY 0.510638 (-1625 3225);
DISPLAY INVISIBLE (-1625 3225);
FORCEADD Q_CAP..1
(-1425 3375);
FORCEPROP 1 LAST LOCATION C353
J 0
(-1375 3475);
DISPLAY 0.978723 (-1375 3475);
PAINT WHITE (-1375 3475);
FORCEPROP 0 LAST $SEC 1
J 0
(-1375 3525);
DISPLAY 0.680851 (-1375 3525);
PAINT MONO (-1375 3525);
DISPLAY INVISIBLE (-1375 3525);
FORCEPROP 0 LAST CDS_SEC 1
J 0
(-1375 3525);
DISPLAY 0.680851 (-1375 3525);
DISPLAY INVISIBLE (-1375 3525);
FORCEPROP 1 LASTPIN (-1425 3475) $PN 1
J 0
(-1415 3455);
DISPLAY 0.787234 (-1415 3455);
PAINT MONO (-1415 3455);
FORCEPROP 1 LASTPIN (-1425 3275) $PN 2
J 0
(-1415 3255);
DISPLAY 0.787234 (-1415 3255);
PAINT MONO (-1415 3255);
FORCEPROP 1 LAST PACK_TYPE 0201
J 0
(-1375 3225);
DISPLAY 0.510638 (-1375 3225);
FORCEPROP 1 LAST TOLERANCE 20%
J 0
(-1375 3325);
DISPLAY 0.510638 (-1375 3325);
FORCEPROP 1 LAST VOLTAGE 4V
J 0
(-1375 3375);
DISPLAY 0.510638 (-1375 3375);
FORCEPROP 1 LAST MATERIAL X6S
J 0
(-1375 3275);
DISPLAY 0.510638 (-1375 3275);
FORCEPROP 1 LAST VALUE 1UF
J 0
(-1375 3425);
DISPLAY 0.510638 (-1375 3425);
FORCEPROP 2 LAST CDS_LIB pure_quanta
J 0
(-1425 3375);
DISPLAY INVISIBLE (-1425 3375);
FORCEPROP 1 LAST PATH I66
J 0
(-1375 3525);
DISPLAY 0.978723 (-1375 3525);
PAINT WHITE (-1375 3525);
DISPLAY INVISIBLE (-1375 3525);
FORCEPROP 1 LAST PART_NUMBER CH-10KMEE00
J 0
(-1375 3225);
DISPLAY 0.510638 (-1375 3225);
DISPLAY INVISIBLE (-1375 3225);
FORCEADD Q_CAP..1
(-3500 4000);
FORCEPROP 1 LAST LOCATION C317
J 0
(-3450 4100);
DISPLAY 0.978723 (-3450 4100);
PAINT WHITE (-3450 4100);
FORCEPROP 0 LAST $SEC 1
J 0
(-3450 4150);
DISPLAY 0.680851 (-3450 4150);
PAINT MONO (-3450 4150);
DISPLAY INVISIBLE (-3450 4150);
FORCEPROP 0 LAST CDS_SEC 1
J 0
(-3450 4150);
DISPLAY 0.680851 (-3450 4150);
DISPLAY INVISIBLE (-3450 4150);
FORCEPROP 1 LASTPIN (-3500 4100) $PN 1
J 0
(-3490 4080);
DISPLAY 0.787234 (-3490 4080);
PAINT MONO (-3490 4080);
FORCEPROP 1 LASTPIN (-3500 3900) $PN 2
J 0
(-3490 3880);
DISPLAY 0.787234 (-3490 3880);
PAINT MONO (-3490 3880);
FORCEPROP 1 LAST MATERIAL X6S
J 0
(-3450 3900);
DISPLAY 0.510638 (-3450 3900);
FORCEPROP 1 LAST PACK_TYPE C0805
J 0
(-3450 3850);
DISPLAY 0.510638 (-3450 3850);
FORCEPROP 1 LAST VALUE 100UF
J 0
(-3450 4050);
DISPLAY 0.510638 (-3450 4050);
FORCEPROP 1 LAST VOLTAGE 4V
J 0
(-3450 4000);
DISPLAY 0.510638 (-3450 4000);
FORCEPROP 1 LAST TOLERANCE 20%
J 0
(-3450 3950);
DISPLAY 0.510638 (-3450 3950);
FORCEPROP 2 LAST CDS_LIB pure_quanta
J 0
(-3500 4000);
DISPLAY INVISIBLE (-3500 4000);
FORCEPROP 1 LAST PATH I67
J 0
(-3450 4150);
DISPLAY 0.978723 (-3450 4150);
PAINT WHITE (-3450 4150);
DISPLAY INVISIBLE (-3450 4150);
FORCEPROP 1 LAST PART_NUMBER CH710KMEA01
J 0
(-3450 3850);
DISPLAY 0.404255 (-3450 3850);
DISPLAY INVISIBLE (-3450 3850);
FORCEADD VCC_CORE..1
(-3500 4650);
FORCEPROP 3 LASTPIN (-3500 4600) SIG_NAME P0V9_CPU1_RT1_2A\g
J 0
(-3490 4610);
DISPLAY 0.659574 (-3490 4610);
PAINT MONO (-3490 4610);
DISPLAY INVISIBLE (-3490 4610);
FORCEPROP 1 LAST HDL_POWER P0V9_CPU1_RT1_2A
J 1
(-3500 4700);
DISPLAY 0.617021 (-3500 4700);
PAINT GREEN (-3500 4700);
FORCEPROP 2 LAST CDS_LIB pure_quanta_power
J 0
(-3500 4650);
DISPLAY INVISIBLE (-3500 4650);
FORCEPROP 1 LAST PATH I68
J 0
(-3450 4675);
DISPLAY 0.872340 (-3450 4675);
PAINT AQUA (-3450 4675);
DISPLAY INVISIBLE (-3450 4675);
FORCEADD Q_CAP..1
(-3275 4000);
FORCEPROP 1 LAST LOCATION C320
J 0
(-3225 4100);
DISPLAY 0.978723 (-3225 4100);
PAINT WHITE (-3225 4100);
FORCEPROP 0 LAST $SEC 1
J 0
(-3225 4150);
DISPLAY 0.680851 (-3225 4150);
PAINT MONO (-3225 4150);
DISPLAY INVISIBLE (-3225 4150);
FORCEPROP 0 LAST CDS_SEC 1
J 0
(-3225 4150);
DISPLAY 0.680851 (-3225 4150);
DISPLAY INVISIBLE (-3225 4150);
FORCEPROP 1 LASTPIN (-3275 4100) $PN 1
J 0
(-3265 4080);
DISPLAY 0.787234 (-3265 4080);
PAINT MONO (-3265 4080);
FORCEPROP 1 LASTPIN (-3275 3900) $PN 2
J 0
(-3265 3880);
DISPLAY 0.787234 (-3265 3880);
PAINT MONO (-3265 3880);
FORCEPROP 1 LAST TOLERANCE 20%
J 0
(-3225 3950);
DISPLAY 0.510638 (-3225 3950);
FORCEPROP 1 LAST MATERIAL X6S
J 0
(-3225 3900);
DISPLAY 0.510638 (-3225 3900);
FORCEPROP 1 LAST VOLTAGE 4V
J 0
(-3225 4000);
DISPLAY 0.510638 (-3225 4000);
FORCEPROP 1 LAST PACK_TYPE C0805
J 0
(-3225 3850);
DISPLAY 0.510638 (-3225 3850);
FORCEPROP 1 LAST VALUE 100UF
J 0
(-3225 4050);
DISPLAY 0.510638 (-3225 4050);
FORCEPROP 2 LAST CDS_LIB pure_quanta
J 0
(-3275 4000);
DISPLAY INVISIBLE (-3275 4000);
FORCEPROP 1 LAST PATH I69
J 0
(-3225 4150);
DISPLAY 0.978723 (-3225 4150);
PAINT WHITE (-3225 4150);
DISPLAY INVISIBLE (-3225 4150);
FORCEPROP 1 LAST PART_NUMBER CH710KMEA01
J 0
(-3225 3850);
DISPLAY 0.404255 (-3225 3850);
DISPLAY INVISIBLE (-3225 3850);
FORCEADD UNIVERSAL_GND..1
(-6525 2500);
FORCEPROP 3 LASTPIN (-6525 2550) SIG_NAME GND\g
J 0
(-6515 2560);
DISPLAY 0.659574 (-6515 2560);
PAINT MONO (-6515 2560);
DISPLAY INVISIBLE (-6515 2560);
FORCEPROP 2 LAST CDS_LIB pure_quanta_power
J 0
(-6525 2500);
DISPLAY INVISIBLE (-6525 2500);
FORCEPROP 1 LAST HDL_POWER GND
J 1
(-6500 2425);
DISPLAY 0.872340 (-6500 2425);
PAINT GREEN (-6500 2425);
DISPLAY INVISIBLE (-6500 2425);
FORCEPROP 1 LAST PATH I7
J 0
(-6450 2500);
DISPLAY 0.872340 (-6450 2500);
PAINT AQUA (-6450 2500);
DISPLAY INVISIBLE (-6450 2500);
FORCEADD Q_CAP..1
(-3050 4000);
FORCEPROP 1 LAST LOCATION C324
J 0
(-3000 4100);
DISPLAY 0.978723 (-3000 4100);
PAINT WHITE (-3000 4100);
FORCEPROP 0 LAST $SEC 1
J 0
(-3000 4150);
DISPLAY 0.680851 (-3000 4150);
PAINT MONO (-3000 4150);
DISPLAY INVISIBLE (-3000 4150);
FORCEPROP 0 LAST CDS_SEC 1
J 0
(-3000 4150);
DISPLAY 0.680851 (-3000 4150);
DISPLAY INVISIBLE (-3000 4150);
FORCEPROP 1 LASTPIN (-3050 4100) $PN 1
J 0
(-3040 4080);
DISPLAY 0.787234 (-3040 4080);
PAINT MONO (-3040 4080);
FORCEPROP 1 LASTPIN (-3050 3900) $PN 2
J 0
(-3040 3880);
DISPLAY 0.787234 (-3040 3880);
PAINT MONO (-3040 3880);
FORCEPROP 1 LAST PACK_TYPE C0805
J 0
(-3000 3850);
DISPLAY 0.510638 (-3000 3850);
FORCEPROP 1 LAST TOLERANCE 20%
J 0
(-3000 3950);
DISPLAY 0.510638 (-3000 3950);
FORCEPROP 1 LAST VOLTAGE 4V
J 0
(-3000 4000);
DISPLAY 0.510638 (-3000 4000);
FORCEPROP 1 LAST MATERIAL X6S
J 0
(-3000 3900);
DISPLAY 0.510638 (-3000 3900);
FORCEPROP 1 LAST VALUE 100UF
J 0
(-3000 4050);
DISPLAY 0.510638 (-3000 4050);
FORCEPROP 2 LAST CDS_LIB pure_quanta
J 0
(-3050 4000);
DISPLAY INVISIBLE (-3050 4000);
FORCEPROP 1 LAST PATH I70
J 0
(-3000 4150);
DISPLAY 0.978723 (-3000 4150);
PAINT WHITE (-3000 4150);
DISPLAY INVISIBLE (-3000 4150);
FORCEPROP 1 LAST PART_NUMBER CH710KMEA01
J 0
(-3000 3850);
DISPLAY 0.404255 (-3000 3850);
DISPLAY INVISIBLE (-3000 3850);
FORCEADD Q_CAP..1
(-2825 4000);
FORCEPROP 1 LAST LOCATION C328
J 0
(-2775 4100);
DISPLAY 0.978723 (-2775 4100);
PAINT WHITE (-2775 4100);
FORCEPROP 0 LAST $SEC 1
J 0
(-2775 4150);
DISPLAY 0.680851 (-2775 4150);
PAINT MONO (-2775 4150);
DISPLAY INVISIBLE (-2775 4150);
FORCEPROP 0 LAST CDS_SEC 1
J 0
(-2775 4150);
DISPLAY 0.680851 (-2775 4150);
DISPLAY INVISIBLE (-2775 4150);
FORCEPROP 1 LASTPIN (-2825 4100) $PN 1
J 0
(-2815 4080);
DISPLAY 0.787234 (-2815 4080);
PAINT MONO (-2815 4080);
FORCEPROP 1 LASTPIN (-2825 3900) $PN 2
J 0
(-2815 3880);
DISPLAY 0.787234 (-2815 3880);
PAINT MONO (-2815 3880);
FORCEPROP 1 LAST TOLERANCE 20%
J 0
(-2775 3950);
DISPLAY 0.510638 (-2775 3950);
FORCEPROP 1 LAST VALUE 100UF
J 0
(-2775 4050);
DISPLAY 0.510638 (-2775 4050);
FORCEPROP 1 LAST MATERIAL X6S
J 0
(-2775 3900);
DISPLAY 0.510638 (-2775 3900);
FORCEPROP 1 LAST VOLTAGE 4V
J 0
(-2775 4000);
DISPLAY 0.510638 (-2775 4000);
FORCEPROP 1 LAST PACK_TYPE C0805
J 0
(-2775 3850);
DISPLAY 0.510638 (-2775 3850);
FORCEPROP 2 LAST CDS_LIB pure_quanta
J 0
(-2825 4000);
DISPLAY INVISIBLE (-2825 4000);
FORCEPROP 1 LAST PATH I71
J 0
(-2775 4150);
DISPLAY 0.978723 (-2775 4150);
PAINT WHITE (-2775 4150);
DISPLAY INVISIBLE (-2775 4150);
FORCEPROP 1 LAST PART_NUMBER CH710KMEA01
J 0
(-2775 3850);
DISPLAY 0.404255 (-2775 3850);
DISPLAY INVISIBLE (-2775 3850);
FORCEADD Q_CAP..1
(-3450 5275);
FORCEPROP 1 LAST LOCATION C323
J 0
(-3400 5375);
DISPLAY 0.978723 (-3400 5375);
PAINT WHITE (-3400 5375);
FORCEPROP 0 LAST $SEC 1
J 0
(-3400 5425);
DISPLAY 0.680851 (-3400 5425);
PAINT MONO (-3400 5425);
DISPLAY INVISIBLE (-3400 5425);
FORCEPROP 0 LAST CDS_SEC 1
J 0
(-3400 5425);
DISPLAY 0.680851 (-3400 5425);
DISPLAY INVISIBLE (-3400 5425);
FORCEPROP 1 LASTPIN (-3450 5375) $PN 1
J 0
(-3440 5355);
DISPLAY 0.787234 (-3440 5355);
PAINT MONO (-3440 5355);
FORCEPROP 1 LASTPIN (-3450 5175) $PN 2
J 0
(-3440 5155);
DISPLAY 0.787234 (-3440 5155);
PAINT MONO (-3440 5155);
FORCEPROP 1 LAST VOLTAGE 4V
J 0
(-3400 5275);
DISPLAY 0.510638 (-3400 5275);
FORCEPROP 1 LAST TOLERANCE 20%
J 0
(-3400 5225);
DISPLAY 0.510638 (-3400 5225);
FORCEPROP 1 LAST PACK_TYPE C0805
J 0
(-3400 5125);
DISPLAY 0.510638 (-3400 5125);
FORCEPROP 1 LAST MATERIAL X6S
J 0
(-3400 5175);
DISPLAY 0.510638 (-3400 5175);
FORCEPROP 1 LAST VALUE 100UF
J 0
(-3400 5325);
DISPLAY 0.510638 (-3400 5325);
FORCEPROP 2 LAST CDS_LIB pure_quanta
J 0
(-3450 5275);
DISPLAY INVISIBLE (-3450 5275);
FORCEPROP 1 LAST PATH I72
J 0
(-3400 5425);
DISPLAY 0.978723 (-3400 5425);
PAINT WHITE (-3400 5425);
DISPLAY INVISIBLE (-3400 5425);
FORCEPROP 1 LAST PART_NUMBER CH710KMEA01
J 0
(-3400 5125);
DISPLAY 0.404255 (-3400 5125);
DISPLAY INVISIBLE (-3400 5125);
FORCEADD Q_CAP..1
(-3175 5275);
FORCEPROP 1 LAST LOCATION C327
J 0
(-3125 5375);
DISPLAY 0.978723 (-3125 5375);
PAINT WHITE (-3125 5375);
FORCEPROP 0 LAST $SEC 1
J 0
(-3125 5425);
DISPLAY 0.680851 (-3125 5425);
PAINT MONO (-3125 5425);
DISPLAY INVISIBLE (-3125 5425);
FORCEPROP 0 LAST CDS_SEC 1
J 0
(-3125 5425);
DISPLAY 0.680851 (-3125 5425);
DISPLAY INVISIBLE (-3125 5425);
FORCEPROP 1 LASTPIN (-3175 5375) $PN 1
J 0
(-3165 5355);
DISPLAY 0.787234 (-3165 5355);
PAINT MONO (-3165 5355);
FORCEPROP 1 LASTPIN (-3175 5175) $PN 2
J 0
(-3165 5155);
DISPLAY 0.787234 (-3165 5155);
PAINT MONO (-3165 5155);
FORCEPROP 1 LAST PACK_TYPE C0402
J 0
(-3125 5125);
DISPLAY 0.510638 (-3125 5125);
FORCEPROP 1 LAST VALUE 22UF
J 0
(-3125 5325);
DISPLAY 0.510638 (-3125 5325);
FORCEPROP 1 LAST VOLTAGE 4V
J 0
(-3125 5275);
DISPLAY 0.510638 (-3125 5275);
FORCEPROP 1 LAST TOLERANCE 20%
J 0
(-3125 5225);
DISPLAY 0.510638 (-3125 5225);
FORCEPROP 1 LAST MATERIAL X6S
J 0
(-3125 5175);
DISPLAY 0.510638 (-3125 5175);
FORCEPROP 2 LAST CDS_LIB pure_quanta
J 0
(-3175 5275);
DISPLAY INVISIBLE (-3175 5275);
FORCEPROP 1 LAST PATH I73
J 0
(-3125 5425);
DISPLAY 0.978723 (-3125 5425);
PAINT WHITE (-3125 5425);
DISPLAY INVISIBLE (-3125 5425);
FORCEPROP 1 LAST PART_NUMBER CH622KMEB02
J 0
(-3125 5125);
DISPLAY 0.978723 (-3125 5125);
DISPLAY INVISIBLE (-3125 5125);
FORCEADD Q_CAP..1
(-2575 4000);
FORCEPROP 1 LAST LOCATION C329
J 0
(-2525 4100);
DISPLAY 0.978723 (-2525 4100);
PAINT WHITE (-2525 4100);
FORCEPROP 0 LAST $SEC 1
J 0
(-2525 4150);
DISPLAY 0.680851 (-2525 4150);
PAINT MONO (-2525 4150);
DISPLAY INVISIBLE (-2525 4150);
FORCEPROP 0 LAST CDS_SEC 1
J 0
(-2525 4150);
DISPLAY 0.680851 (-2525 4150);
DISPLAY INVISIBLE (-2525 4150);
FORCEPROP 1 LASTPIN (-2575 4100) $PN 1
J 0
(-2565 4080);
DISPLAY 0.787234 (-2565 4080);
PAINT MONO (-2565 4080);
FORCEPROP 1 LASTPIN (-2575 3900) $PN 2
J 0
(-2565 3880);
DISPLAY 0.787234 (-2565 3880);
PAINT MONO (-2565 3880);
FORCEPROP 1 LAST VALUE 22UF
J 0
(-2525 4050);
DISPLAY 0.510638 (-2525 4050);
FORCEPROP 1 LAST TOLERANCE 20%
J 0
(-2525 3950);
DISPLAY 0.510638 (-2525 3950);
FORCEPROP 1 LAST MATERIAL X6S
J 0
(-2525 3900);
DISPLAY 0.510638 (-2525 3900);
FORCEPROP 1 LAST PACK_TYPE C0402
J 0
(-2525 3850);
DISPLAY 0.510638 (-2525 3850);
FORCEPROP 1 LAST VOLTAGE 4V
J 0
(-2525 4000);
DISPLAY 0.510638 (-2525 4000);
FORCEPROP 2 LAST CDS_LIB pure_quanta
J 0
(-2575 4000);
DISPLAY INVISIBLE (-2575 4000);
FORCEPROP 1 LAST PATH I74
J 0
(-2525 4150);
DISPLAY 0.978723 (-2525 4150);
PAINT WHITE (-2525 4150);
DISPLAY INVISIBLE (-2525 4150);
FORCEPROP 1 LAST PART_NUMBER CH622KMEB02
J 0
(-2525 3850);
DISPLAY 0.978723 (-2525 3850);
DISPLAY INVISIBLE (-2525 3850);
FORCEADD Q_CAP..1
(-2350 4000);
FORCEPROP 1 LAST LOCATION C335
J 0
(-2300 4100);
DISPLAY 0.978723 (-2300 4100);
PAINT WHITE (-2300 4100);
FORCEPROP 0 LAST $SEC 1
J 0
(-2300 4150);
DISPLAY 0.680851 (-2300 4150);
PAINT MONO (-2300 4150);
DISPLAY INVISIBLE (-2300 4150);
FORCEPROP 0 LAST CDS_SEC 1
J 0
(-2300 4150);
DISPLAY 0.680851 (-2300 4150);
DISPLAY INVISIBLE (-2300 4150);
FORCEPROP 1 LASTPIN (-2350 4100) $PN 1
J 0
(-2340 4080);
DISPLAY 0.787234 (-2340 4080);
PAINT MONO (-2340 4080);
FORCEPROP 1 LASTPIN (-2350 3900) $PN 2
J 0
(-2340 3880);
DISPLAY 0.787234 (-2340 3880);
PAINT MONO (-2340 3880);
FORCEPROP 1 LAST VALUE 22UF
J 0
(-2300 4050);
DISPLAY 0.510638 (-2300 4050);
FORCEPROP 1 LAST MATERIAL X6S
J 0
(-2300 3900);
DISPLAY 0.510638 (-2300 3900);
FORCEPROP 1 LAST TOLERANCE 20%
J 0
(-2300 3950);
DISPLAY 0.510638 (-2300 3950);
FORCEPROP 1 LAST VOLTAGE 4V
J 0
(-2300 4000);
DISPLAY 0.510638 (-2300 4000);
FORCEPROP 1 LAST PACK_TYPE C0402
J 0
(-2300 3850);
DISPLAY 0.510638 (-2300 3850);
FORCEPROP 2 LAST CDS_LIB pure_quanta
J 0
(-2350 4000);
DISPLAY INVISIBLE (-2350 4000);
FORCEPROP 1 LAST PATH I75
J 0
(-2300 4150);
DISPLAY 0.978723 (-2300 4150);
PAINT WHITE (-2300 4150);
DISPLAY INVISIBLE (-2300 4150);
FORCEPROP 1 LAST PART_NUMBER CH622KMEB02
J 0
(-2300 3850);
DISPLAY 0.978723 (-2300 3850);
DISPLAY INVISIBLE (-2300 3850);
FORCEADD Q_CAP..1
(-2125 4000);
FORCEPROP 1 LAST LOCATION C351
J 0
(-2075 4100);
DISPLAY 0.978723 (-2075 4100);
PAINT WHITE (-2075 4100);
FORCEPROP 0 LAST $SEC 1
J 0
(-2075 4150);
DISPLAY 0.680851 (-2075 4150);
PAINT MONO (-2075 4150);
DISPLAY INVISIBLE (-2075 4150);
FORCEPROP 0 LAST CDS_SEC 1
J 0
(-2075 4150);
DISPLAY 0.680851 (-2075 4150);
DISPLAY INVISIBLE (-2075 4150);
FORCEPROP 1 LASTPIN (-2125 4100) $PN 1
J 0
(-2115 4080);
DISPLAY 0.787234 (-2115 4080);
PAINT MONO (-2115 4080);
FORCEPROP 1 LASTPIN (-2125 3900) $PN 2
J 0
(-2115 3880);
DISPLAY 0.787234 (-2115 3880);
PAINT MONO (-2115 3880);
FORCEPROP 1 LAST PACK_TYPE C0402
J 0
(-2075 3850);
DISPLAY 0.510638 (-2075 3850);
FORCEPROP 1 LAST VOLTAGE 4V
J 0
(-2075 4000);
DISPLAY 0.510638 (-2075 4000);
FORCEPROP 1 LAST VALUE 22UF
J 0
(-2075 4050);
DISPLAY 0.510638 (-2075 4050);
FORCEPROP 1 LAST TOLERANCE 20%
J 0
(-2075 3950);
DISPLAY 0.510638 (-2075 3950);
FORCEPROP 1 LAST MATERIAL X6S
J 0
(-2075 3900);
DISPLAY 0.510638 (-2075 3900);
FORCEPROP 2 LAST CDS_LIB pure_quanta
J 0
(-2125 4000);
DISPLAY INVISIBLE (-2125 4000);
FORCEPROP 1 LAST PATH I76
J 0
(-2075 4150);
DISPLAY 0.978723 (-2075 4150);
PAINT WHITE (-2075 4150);
DISPLAY INVISIBLE (-2075 4150);
FORCEPROP 1 LAST PART_NUMBER CH622KMEB02
J 0
(-2075 3850);
DISPLAY 0.978723 (-2075 3850);
DISPLAY INVISIBLE (-2075 3850);
FORCEADD Q_CAP..1
(-1900 4000);
FORCEPROP 1 LAST LOCATION C318
J 0
(-1850 4100);
DISPLAY 0.978723 (-1850 4100);
PAINT WHITE (-1850 4100);
FORCEPROP 0 LAST $SEC 1
J 0
(-1850 4150);
DISPLAY 0.680851 (-1850 4150);
PAINT MONO (-1850 4150);
DISPLAY INVISIBLE (-1850 4150);
FORCEPROP 0 LAST CDS_SEC 1
J 0
(-1850 4150);
DISPLAY 0.680851 (-1850 4150);
DISPLAY INVISIBLE (-1850 4150);
FORCEPROP 1 LASTPIN (-1900 4100) $PN 1
J 0
(-1890 4080);
DISPLAY 0.787234 (-1890 4080);
PAINT MONO (-1890 4080);
FORCEPROP 1 LASTPIN (-1900 3900) $PN 2
J 0
(-1890 3880);
DISPLAY 0.787234 (-1890 3880);
PAINT MONO (-1890 3880);
FORCEPROP 1 LAST VALUE 22UF
J 0
(-1850 4050);
DISPLAY 0.510638 (-1850 4050);
FORCEPROP 1 LAST VOLTAGE 4V
J 0
(-1850 4000);
DISPLAY 0.510638 (-1850 4000);
FORCEPROP 1 LAST MATERIAL X6S
J 0
(-1850 3900);
DISPLAY 0.510638 (-1850 3900);
FORCEPROP 1 LAST TOLERANCE 20%
J 0
(-1850 3950);
DISPLAY 0.510638 (-1850 3950);
FORCEPROP 1 LAST PACK_TYPE C0402
J 0
(-1850 3850);
DISPLAY 0.510638 (-1850 3850);
FORCEPROP 2 LAST CDS_LIB pure_quanta
J 0
(-1900 4000);
DISPLAY INVISIBLE (-1900 4000);
FORCEPROP 1 LAST PATH I77
J 0
(-1850 4150);
DISPLAY 0.978723 (-1850 4150);
PAINT WHITE (-1850 4150);
DISPLAY INVISIBLE (-1850 4150);
FORCEPROP 1 LAST PART_NUMBER CH622KMEB02
J 0
(-1850 3850);
DISPLAY 0.978723 (-1850 3850);
DISPLAY INVISIBLE (-1850 3850);
FORCEADD Q_CAP..1
(-2550 5250);
FORCEPROP 1 LAST LOCATION C338
J 0
(-2500 5350);
DISPLAY 0.978723 (-2500 5350);
PAINT WHITE (-2500 5350);
FORCEPROP 0 LAST $SEC 1
J 0
(-2500 5400);
DISPLAY 0.680851 (-2500 5400);
PAINT MONO (-2500 5400);
DISPLAY INVISIBLE (-2500 5400);
FORCEPROP 0 LAST CDS_SEC 1
J 0
(-2500 5400);
DISPLAY 0.680851 (-2500 5400);
DISPLAY INVISIBLE (-2500 5400);
FORCEPROP 1 LASTPIN (-2550 5350) $PN 1
J 0
(-2540 5330);
DISPLAY 0.787234 (-2540 5330);
PAINT MONO (-2540 5330);
FORCEPROP 1 LASTPIN (-2550 5150) $PN 2
J 0
(-2540 5130);
DISPLAY 0.787234 (-2540 5130);
PAINT MONO (-2540 5130);
FORCEPROP 1 LAST PACK_TYPE 0402
J 0
(-2500 5100);
DISPLAY 0.510638 (-2500 5100);
FORCEPROP 1 LAST VALUE 4.7UF
J 0
(-2500 5300);
DISPLAY 0.510638 (-2500 5300);
FORCEPROP 1 LAST VOLTAGE 6.3V
J 0
(-2500 5250);
DISPLAY 0.510638 (-2500 5250);
FORCEPROP 1 LAST MATERIAL X6S
J 0
(-2500 5150);
DISPLAY 0.510638 (-2500 5150);
FORCEPROP 1 LAST TOLERANCE 20%
J 0
(-2500 5200);
DISPLAY 0.510638 (-2500 5200);
FORCEPROP 2 LAST CDS_LIB pure_quanta
J 0
(-2550 5250);
DISPLAY INVISIBLE (-2550 5250);
FORCEPROP 1 LAST PATH I78
J 0
(-2500 5400);
DISPLAY 0.978723 (-2500 5400);
PAINT WHITE (-2500 5400);
DISPLAY INVISIBLE (-2500 5400);
FORCEPROP 1 LAST PART_NUMBER CH5471MEB01
J 0
(-2500 5100);
DISPLAY 0.978723 (-2500 5100);
DISPLAY INVISIBLE (-2500 5100);
FORCEADD Q_CAP..1
(-2250 5250);
FORCEPROP 1 LAST LOCATION C342
J 0
(-2200 5350);
DISPLAY 0.978723 (-2200 5350);
PAINT WHITE (-2200 5350);
FORCEPROP 0 LAST $SEC 1
J 0
(-2200 5400);
DISPLAY 0.680851 (-2200 5400);
PAINT MONO (-2200 5400);
DISPLAY INVISIBLE (-2200 5400);
FORCEPROP 0 LAST CDS_SEC 1
J 0
(-2200 5400);
DISPLAY 0.680851 (-2200 5400);
DISPLAY INVISIBLE (-2200 5400);
FORCEPROP 1 LASTPIN (-2250 5350) $PN 1
J 0
(-2240 5330);
DISPLAY 0.787234 (-2240 5330);
PAINT MONO (-2240 5330);
FORCEPROP 1 LASTPIN (-2250 5150) $PN 2
J 0
(-2240 5130);
DISPLAY 0.787234 (-2240 5130);
PAINT MONO (-2240 5130);
FORCEPROP 1 LAST PACK_TYPE 0201
J 0
(-2200 5100);
DISPLAY 0.510638 (-2200 5100);
FORCEPROP 1 LAST TOLERANCE 20%
J 0
(-2200 5200);
DISPLAY 0.510638 (-2200 5200);
FORCEPROP 1 LAST VALUE 1UF
J 0
(-2200 5300);
DISPLAY 0.510638 (-2200 5300);
FORCEPROP 1 LAST VOLTAGE 4V
J 0
(-2200 5250);
DISPLAY 0.510638 (-2200 5250);
FORCEPROP 1 LAST MATERIAL X6S
J 0
(-2200 5150);
DISPLAY 0.510638 (-2200 5150);
FORCEPROP 2 LAST CDS_LIB pure_quanta
J 0
(-2250 5250);
DISPLAY INVISIBLE (-2250 5250);
FORCEPROP 1 LAST PATH I79
J 0
(-2200 5400);
DISPLAY 0.978723 (-2200 5400);
PAINT WHITE (-2200 5400);
DISPLAY INVISIBLE (-2200 5400);
FORCEPROP 1 LAST PART_NUMBER CH-10KMEE00
J 0
(-2200 5100);
DISPLAY 0.510638 (-2200 5100);
DISPLAY INVISIBLE (-2200 5100);
FORCEADD Q_CAP..1
(-6800 2925);
FORCEPROP 1 LAST LOCATION C203
J 0
(-6750 3025);
DISPLAY 0.638298 (-6750 3025);
PAINT WHITE (-6750 3025);
FORCEPROP 0 LAST $SEC 1
J 0
(-6750 3075);
DISPLAY 0.680851 (-6750 3075);
PAINT MONO (-6750 3075);
DISPLAY INVISIBLE (-6750 3075);
FORCEPROP 0 LAST CDS_SEC 1
J 0
(-6750 3075);
DISPLAY 0.680851 (-6750 3075);
DISPLAY INVISIBLE (-6750 3075);
FORCEPROP 1 LASTPIN (-6800 3025) $PN 1
J 0
(-6790 3005);
DISPLAY 0.787234 (-6790 3005);
PAINT MONO (-6790 3005);
FORCEPROP 1 LASTPIN (-6800 2825) $PN 2
J 0
(-6790 2805);
DISPLAY 0.787234 (-6790 2805);
PAINT MONO (-6790 2805);
FORCEPROP 1 LAST VOLTAGE 4V
J 0
(-6750 2925);
DISPLAY 0.510638 (-6750 2925);
FORCEPROP 1 LAST TOLERANCE 20%
J 0
(-6750 2875);
DISPLAY 0.510638 (-6750 2875);
FORCEPROP 1 LAST VALUE 1UF
J 0
(-6750 2975);
DISPLAY 0.510638 (-6750 2975);
FORCEPROP 1 LAST MATERIAL X6S
J 0
(-6750 2825);
DISPLAY 0.510638 (-6750 2825);
FORCEPROP 1 LAST PACK_TYPE 0201
J 0
(-6750 2775);
DISPLAY 0.510638 (-6750 2775);
FORCEPROP 2 LAST CDS_LIB pure_quanta
J 0
(-6800 2925);
DISPLAY INVISIBLE (-6800 2925);
FORCEPROP 1 LAST PATH I8
J 0
(-6750 3075);
DISPLAY 0.978723 (-6750 3075);
PAINT WHITE (-6750 3075);
DISPLAY INVISIBLE (-6750 3075);
FORCEPROP 1 LAST PART_NUMBER CH-10KMEE00
J 0
(-6750 2775);
DISPLAY 0.510638 (-6750 2775);
DISPLAY INVISIBLE (-6750 2775);
FORCEADD Q_CAP..1
(-1600 4000);
FORCEPROP 1 LAST LOCATION C339
J 0
(-1550 4100);
DISPLAY 0.978723 (-1550 4100);
PAINT WHITE (-1550 4100);
FORCEPROP 0 LAST $SEC 1
J 0
(-1550 4150);
DISPLAY 0.680851 (-1550 4150);
PAINT MONO (-1550 4150);
DISPLAY INVISIBLE (-1550 4150);
FORCEPROP 0 LAST CDS_SEC 1
J 0
(-1550 4150);
DISPLAY 0.680851 (-1550 4150);
DISPLAY INVISIBLE (-1550 4150);
FORCEPROP 1 LASTPIN (-1600 4100) $PN 1
J 0
(-1590 4080);
DISPLAY 0.787234 (-1590 4080);
PAINT MONO (-1590 4080);
FORCEPROP 1 LASTPIN (-1600 3900) $PN 2
J 0
(-1590 3880);
DISPLAY 0.787234 (-1590 3880);
PAINT MONO (-1590 3880);
FORCEPROP 1 LAST PACK_TYPE C0402
J 0
(-1550 3850);
DISPLAY 0.510638 (-1550 3850);
FORCEPROP 1 LAST MATERIAL X6S
J 0
(-1550 3900);
DISPLAY 0.510638 (-1550 3900);
FORCEPROP 1 LAST VALUE 10UF
J 0
(-1550 4050);
DISPLAY 0.510638 (-1550 4050);
FORCEPROP 1 LAST VOLTAGE 6.3V
J 0
(-1550 4000);
DISPLAY 0.510638 (-1550 4000);
FORCEPROP 1 LAST TOLERANCE 20%
J 0
(-1550 3950);
DISPLAY 0.510638 (-1550 3950);
FORCEPROP 2 LAST CDS_LIB pure_quanta
J 0
(-1600 4000);
DISPLAY INVISIBLE (-1600 4000);
FORCEPROP 1 LAST PATH I80
J 0
(-1550 4150);
DISPLAY 0.978723 (-1550 4150);
PAINT WHITE (-1550 4150);
DISPLAY INVISIBLE (-1550 4150);
FORCEPROP 1 LAST PART_NUMBER CH6101MEB01
J 0
(-1550 3850);
DISPLAY 0.978723 (-1550 3850);
DISPLAY INVISIBLE (-1550 3850);
FORCEADD Q_CAP..1
(-1300 4000);
FORCEPROP 1 LAST LOCATION C354
J 0
(-1250 4100);
DISPLAY 0.978723 (-1250 4100);
PAINT WHITE (-1250 4100);
FORCEPROP 0 LAST $SEC 1
J 0
(-1250 4150);
DISPLAY 0.680851 (-1250 4150);
PAINT MONO (-1250 4150);
DISPLAY INVISIBLE (-1250 4150);
FORCEPROP 0 LAST CDS_SEC 1
J 0
(-1250 4150);
DISPLAY 0.680851 (-1250 4150);
DISPLAY INVISIBLE (-1250 4150);
FORCEPROP 1 LASTPIN (-1300 4100) $PN 1
J 0
(-1290 4080);
DISPLAY 0.787234 (-1290 4080);
PAINT MONO (-1290 4080);
FORCEPROP 1 LASTPIN (-1300 3900) $PN 2
J 0
(-1290 3880);
DISPLAY 0.787234 (-1290 3880);
PAINT MONO (-1290 3880);
FORCEPROP 1 LAST PACK_TYPE C0402
J 0
(-1250 3850);
DISPLAY 0.510638 (-1250 3850);
FORCEPROP 1 LAST MATERIAL X6S
J 0
(-1250 3900);
DISPLAY 0.510638 (-1250 3900);
FORCEPROP 1 LAST TOLERANCE 20%
J 0
(-1250 3950);
DISPLAY 0.510638 (-1250 3950);
FORCEPROP 1 LAST VOLTAGE 6.3V
J 0
(-1250 4000);
DISPLAY 0.510638 (-1250 4000);
FORCEPROP 1 LAST VALUE 10UF
J 0
(-1250 4050);
DISPLAY 0.510638 (-1250 4050);
FORCEPROP 2 LAST CDS_LIB pure_quanta
J 0
(-1300 4000);
DISPLAY INVISIBLE (-1300 4000);
FORCEPROP 1 LAST PATH I81
J 0
(-1250 4150);
DISPLAY 0.978723 (-1250 4150);
PAINT WHITE (-1250 4150);
DISPLAY INVISIBLE (-1250 4150);
FORCEPROP 1 LAST PART_NUMBER CH6101MEB01
J 0
(-1250 3850);
DISPLAY 0.978723 (-1250 3850);
DISPLAY INVISIBLE (-1250 3850);
FORCEADD Q_CAP..1
(-1425 5225);
FORCEPROP 1 LAST LOCATION C300
J 0
(-1375 5325);
DISPLAY 0.978723 (-1375 5325);
PAINT WHITE (-1375 5325);
FORCEPROP 0 LAST $SEC 1
J 0
(-1375 5375);
DISPLAY 0.680851 (-1375 5375);
PAINT MONO (-1375 5375);
DISPLAY INVISIBLE (-1375 5375);
FORCEPROP 0 LAST CDS_SEC 1
J 0
(-1375 5375);
DISPLAY 0.680851 (-1375 5375);
DISPLAY INVISIBLE (-1375 5375);
FORCEPROP 1 LASTPIN (-1425 5325) $PN 1
J 0
(-1415 5305);
DISPLAY 0.787234 (-1415 5305);
PAINT MONO (-1415 5305);
FORCEPROP 1 LASTPIN (-1425 5125) $PN 2
J 0
(-1415 5105);
DISPLAY 0.787234 (-1415 5105);
PAINT MONO (-1415 5105);
FORCEPROP 1 LAST MATERIAL X7S
J 0
(-1375 5125);
DISPLAY 0.638298 (-1375 5125);
FORCEPROP 1 LAST VOLTAGE 10V
J 0
(-1375 5225);
DISPLAY 0.638298 (-1375 5225);
FORCEPROP 1 LAST VALUE 0.1UF
J 0
(-1375 5275);
DISPLAY 0.638298 (-1375 5275);
FORCEPROP 1 LAST TOLERANCE 10%
J 0
(-1375 5175);
DISPLAY 0.638298 (-1375 5175);
FORCEPROP 1 LAST PACK_TYPE C0201
J 0
(-1375 5075);
DISPLAY 0.638298 (-1375 5075);
FORCEPROP 2 LAST CDS_LIB pure_quanta
J 0
(-1425 5225);
DISPLAY INVISIBLE (-1425 5225);
FORCEPROP 1 LAST PATH I82
J 0
(-1375 5375);
DISPLAY 0.978723 (-1375 5375);
PAINT WHITE (-1375 5375);
DISPLAY INVISIBLE (-1375 5375);
FORCEPROP 1 LAST PART_NUMBER CH4102K6E00
J 0
(-1375 5075);
DISPLAY 0.978723 (-1375 5075);
DISPLAY INVISIBLE (-1375 5075);
FORCEADD UNIVERSAL_GND..1
(-1225 4825);
FORCEPROP 3 LASTPIN (-1225 4875) SIG_NAME GND\g
J 0
(-1215 4885);
DISPLAY 0.659574 (-1215 4885);
PAINT MONO (-1215 4885);
DISPLAY INVISIBLE (-1215 4885);
FORCEPROP 2 LAST CDS_LIB pure_quanta_power
J 0
(-1225 4825);
DISPLAY INVISIBLE (-1225 4825);
FORCEPROP 1 LAST HDL_POWER GND
J 1
(-1200 4750);
DISPLAY 0.872340 (-1200 4750);
PAINT GREEN (-1200 4750);
DISPLAY INVISIBLE (-1200 4750);
FORCEPROP 1 LAST PATH I83
J 0
(-1150 4825);
DISPLAY 0.872340 (-1150 4825);
PAINT AQUA (-1150 4825);
DISPLAY INVISIBLE (-1150 4825);
FORCEADD Q_CAP..1
(-1150 5225);
FORCEPROP 1 LAST LOCATION C311
J 0
(-1100 5325);
DISPLAY 0.978723 (-1100 5325);
PAINT WHITE (-1100 5325);
FORCEPROP 0 LAST $SEC 1
J 0
(-1100 5375);
DISPLAY 0.680851 (-1100 5375);
PAINT MONO (-1100 5375);
DISPLAY INVISIBLE (-1100 5375);
FORCEPROP 0 LAST CDS_SEC 1
J 0
(-1100 5375);
DISPLAY 0.680851 (-1100 5375);
DISPLAY INVISIBLE (-1100 5375);
FORCEPROP 1 LASTPIN (-1150 5325) $PN 1
J 0
(-1140 5305);
DISPLAY 0.787234 (-1140 5305);
PAINT MONO (-1140 5305);
FORCEPROP 1 LASTPIN (-1150 5125) $PN 2
J 0
(-1140 5105);
DISPLAY 0.787234 (-1140 5105);
PAINT MONO (-1140 5105);
FORCEPROP 1 LAST PACK_TYPE C0201
J 0
(-1100 5075);
DISPLAY 0.638298 (-1100 5075);
FORCEPROP 1 LAST MATERIAL X7S
J 0
(-1100 5125);
DISPLAY 0.638298 (-1100 5125);
FORCEPROP 1 LAST VOLTAGE 10V
J 0
(-1100 5225);
DISPLAY 0.638298 (-1100 5225);
FORCEPROP 1 LAST TOLERANCE 10%
J 0
(-1100 5175);
DISPLAY 0.638298 (-1100 5175);
FORCEPROP 1 LAST VALUE 0.1UF
J 0
(-1100 5275);
DISPLAY 0.638298 (-1100 5275);
FORCEPROP 2 LAST CDS_LIB pure_quanta
J 0
(-1150 5225);
DISPLAY INVISIBLE (-1150 5225);
FORCEPROP 1 LAST PATH I84
J 0
(-1100 5375);
DISPLAY 0.978723 (-1100 5375);
PAINT WHITE (-1100 5375);
DISPLAY INVISIBLE (-1100 5375);
FORCEPROP 1 LAST PART_NUMBER CH4102K6E00
J 0
(-1100 5075);
DISPLAY 0.978723 (-1100 5075);
DISPLAY INVISIBLE (-1100 5075);
FORCEADD Q_CAP..1
(-1675 5225);
FORCEPROP 1 LAST LOCATION C292
J 0
(-1625 5325);
DISPLAY 0.978723 (-1625 5325);
PAINT WHITE (-1625 5325);
FORCEPROP 0 LAST $SEC 1
J 0
(-1625 5375);
DISPLAY 0.680851 (-1625 5375);
PAINT MONO (-1625 5375);
DISPLAY INVISIBLE (-1625 5375);
FORCEPROP 0 LAST CDS_SEC 1
J 0
(-1625 5375);
DISPLAY 0.680851 (-1625 5375);
DISPLAY INVISIBLE (-1625 5375);
FORCEPROP 1 LASTPIN (-1675 5325) $PN 1
J 0
(-1665 5305);
DISPLAY 0.787234 (-1665 5305);
PAINT MONO (-1665 5305);
FORCEPROP 1 LASTPIN (-1675 5125) $PN 2
J 0
(-1665 5105);
DISPLAY 0.787234 (-1665 5105);
PAINT MONO (-1665 5105);
FORCEPROP 1 LAST PACK_TYPE C0201
J 0
(-1625 5075);
DISPLAY 0.638298 (-1625 5075);
FORCEPROP 1 LAST MATERIAL X7S
J 0
(-1625 5125);
DISPLAY 0.638298 (-1625 5125);
FORCEPROP 1 LAST VOLTAGE 10V
J 0
(-1625 5225);
DISPLAY 0.638298 (-1625 5225);
FORCEPROP 1 LAST TOLERANCE 10%
J 0
(-1625 5175);
DISPLAY 0.638298 (-1625 5175);
FORCEPROP 1 LAST VALUE 0.1UF
J 0
(-1625 5275);
DISPLAY 0.638298 (-1625 5275);
FORCEPROP 2 LAST CDS_LIB pure_quanta
J 0
(-1675 5225);
DISPLAY INVISIBLE (-1675 5225);
FORCEPROP 1 LAST PATH I85
J 0
(-1625 5375);
DISPLAY 0.978723 (-1625 5375);
PAINT WHITE (-1625 5375);
DISPLAY INVISIBLE (-1625 5375);
FORCEPROP 1 LAST PART_NUMBER CH4102K6E00
J 0
(-1625 5075);
DISPLAY 0.978723 (-1625 5075);
DISPLAY INVISIBLE (-1625 5075);
FORCEADD Q_CAP..1
(-1950 5225);
FORCEPROP 1 LAST LOCATION C290
J 0
(-1900 5325);
DISPLAY 0.978723 (-1900 5325);
PAINT WHITE (-1900 5325);
FORCEPROP 0 LAST $SEC 1
J 0
(-1900 5375);
DISPLAY 0.680851 (-1900 5375);
PAINT MONO (-1900 5375);
DISPLAY INVISIBLE (-1900 5375);
FORCEPROP 0 LAST CDS_SEC 1
J 0
(-1900 5375);
DISPLAY 0.680851 (-1900 5375);
DISPLAY INVISIBLE (-1900 5375);
FORCEPROP 1 LASTPIN (-1950 5325) $PN 1
J 0
(-1940 5305);
DISPLAY 0.787234 (-1940 5305);
PAINT MONO (-1940 5305);
FORCEPROP 1 LASTPIN (-1950 5125) $PN 2
J 0
(-1940 5105);
DISPLAY 0.787234 (-1940 5105);
PAINT MONO (-1940 5105);
FORCEPROP 1 LAST VOLTAGE 10V
J 0
(-1900 5225);
DISPLAY 0.638298 (-1900 5225);
FORCEPROP 1 LAST VALUE 0.1UF
J 0
(-1900 5275);
DISPLAY 0.638298 (-1900 5275);
FORCEPROP 1 LAST PACK_TYPE C0201
J 0
(-1900 5075);
DISPLAY 0.638298 (-1900 5075);
FORCEPROP 1 LAST MATERIAL X7S
J 0
(-1900 5125);
DISPLAY 0.638298 (-1900 5125);
FORCEPROP 1 LAST TOLERANCE 10%
J 0
(-1900 5175);
DISPLAY 0.638298 (-1900 5175);
FORCEPROP 2 LAST CDS_LIB pure_quanta
J 0
(-1950 5225);
DISPLAY INVISIBLE (-1950 5225);
FORCEPROP 1 LAST PATH I86
J 0
(-1900 5375);
DISPLAY 0.978723 (-1900 5375);
PAINT WHITE (-1900 5375);
DISPLAY INVISIBLE (-1900 5375);
FORCEPROP 1 LAST PART_NUMBER CH4102K6E00
J 0
(-1900 5075);
DISPLAY 0.978723 (-1900 5075);
DISPLAY INVISIBLE (-1900 5075);
FORCEADD Q_CAP..1
(-2850 5250);
FORCEPROP 1 LAST LOCATION C333
J 0
(-2800 5350);
DISPLAY 0.978723 (-2800 5350);
PAINT WHITE (-2800 5350);
FORCEPROP 0 LAST $SEC 1
J 0
(-2800 5400);
DISPLAY 0.680851 (-2800 5400);
PAINT MONO (-2800 5400);
DISPLAY INVISIBLE (-2800 5400);
FORCEPROP 0 LAST CDS_SEC 1
J 0
(-2800 5400);
DISPLAY 0.680851 (-2800 5400);
DISPLAY INVISIBLE (-2800 5400);
FORCEPROP 1 LASTPIN (-2850 5350) $PN 1
J 0
(-2840 5330);
DISPLAY 0.787234 (-2840 5330);
PAINT MONO (-2840 5330);
FORCEPROP 1 LASTPIN (-2850 5150) $PN 2
J 0
(-2840 5130);
DISPLAY 0.787234 (-2840 5130);
PAINT MONO (-2840 5130);
FORCEPROP 1 LAST PACK_TYPE C0402
J 0
(-2800 5100);
DISPLAY 0.510638 (-2800 5100);
FORCEPROP 1 LAST MATERIAL X6S
J 0
(-2800 5150);
DISPLAY 0.510638 (-2800 5150);
FORCEPROP 1 LAST VOLTAGE 6.3V
J 0
(-2800 5250);
DISPLAY 0.510638 (-2800 5250);
FORCEPROP 1 LAST TOLERANCE 20%
J 0
(-2800 5200);
DISPLAY 0.510638 (-2800 5200);
FORCEPROP 1 LAST VALUE 10UF
J 0
(-2800 5300);
DISPLAY 0.510638 (-2800 5300);
FORCEPROP 2 LAST CDS_LIB pure_quanta
J 0
(-2850 5250);
DISPLAY INVISIBLE (-2850 5250);
FORCEPROP 1 LAST PATH I87
J 0
(-2800 5400);
DISPLAY 0.978723 (-2800 5400);
PAINT WHITE (-2800 5400);
DISPLAY INVISIBLE (-2800 5400);
FORCEPROP 1 LAST PART_NUMBER CH6101MEB01
J 0
(-2800 5100);
DISPLAY 0.978723 (-2800 5100);
DISPLAY INVISIBLE (-2800 5100);
FORCEADD Q_INDUCTOR..1
R 3
(-8250 3925);
FORCEPROP 1 LAST LOCATION L31
R 1
J 2
(-8410 4050);
DISPLAY 0.723404 (-8410 4050);
PAINT GREEN (-8410 4050);
FORCEPROP 0 LAST $SEC 1
R 1
J 0
(-8225 4050);
DISPLAY 0.680851 (-8225 4050);
PAINT MONO (-8225 4050);
DISPLAY INVISIBLE (-8225 4050);
FORCEPROP 0 LAST CDS_SEC 1
R 1
J 0
(-8225 4050);
DISPLAY 0.680851 (-8225 4050);
DISPLAY INVISIBLE (-8225 4050);
FORCEPROP 0 LASTPIN (-8225 4025) $PN 1
R 1
J 0
(-8235 4035);
DISPLAY 0.680851 (-8235 4035);
PAINT MONO (-8235 4035);
FORCEPROP 0 LASTPIN (-8225 3825) $PN 2
R 1
J 2
(-8235 3815);
DISPLAY 0.680851 (-8235 3815);
PAINT MONO (-8235 3815);
FORCEPROP 2 LAST PACK_TYPE SMLF
R 1
J 2
(-8450 4050);
DISPLAY 0.553191 (-8450 4050);
FORCEPROP 1 LAST MATERIAL IND
R 1
J 2
(-8305 4050);
DISPLAY 0.574468 (-8305 4050);
PAINT GREEN (-8305 4050);
FORCEPROP 2 LAST VALUE BLM15PD121SN1D/1300MA
R 1
J 2
(-8500 4050);
DISPLAY 0.553191 (-8500 4050);
FORCEPROP 1 LAST NEEDS_NO_SIZE TRUE
R 1
J 2
(-8250 3925);
DISPLAY 0.468085 (-8250 3925);
PAINT GREEN (-8250 3925);
DISPLAY INVISIBLE (-8250 3925);
FORCEPROP 2 LAST CDS_LIB pure_quanta
J 0
(-8250 3925);
DISPLAY INVISIBLE (-8250 3925);
FORCEPROP 1 LAST PATH I88
R 1
J 2
(-8305 3850);
DISPLAY 0.723404 (-8305 3850);
PAINT GREEN (-8305 3850);
DISPLAY INVISIBLE (-8305 3850);
FORCEPROP 1 LAST PART_NUMBER CX5PD121000
R 1
J 2
(-8350 4050);
DISPLAY 0.574468 (-8350 4050);
PAINT GREEN (-8350 4050);
DISPLAY INVISIBLE (-8350 4050);
FORCEADD Q_RES..2
(-8125 3900);
FORCEPROP 1 LAST LOCATION R704
J 0
(-8080 4025);
DISPLAY 0.808511 (-8080 4025);
FORCEPROP 0 LAST $SEC 1
J 0
(-8075 4075);
DISPLAY 0.680851 (-8075 4075);
PAINT MONO (-8075 4075);
DISPLAY INVISIBLE (-8075 4075);
FORCEPROP 0 LAST CDS_SEC 1
J 0
(-8075 4075);
DISPLAY 0.680851 (-8075 4075);
DISPLAY INVISIBLE (-8075 4075);
FORCEPROP 1 LASTPIN (-8125 4000) $PN 1
J 0
(-8120 3962);
DISPLAY 0.787234 (-8120 3962);
PAINT MONO (-8120 3962);
FORCEPROP 1 LASTPIN (-8125 3800) $PN 2
J 0
(-8120 3810);
DISPLAY 0.787234 (-8120 3810);
PAINT MONO (-8120 3810);
FORCEPROP 1 LAST VALUE 0
J 0
(-8080 3975);
DISPLAY 0.638298 (-8080 3975);
FORCEPROP 1 LAST MATERIAL EMPTY
J 0
(-8085 3825);
DISPLAY 0.638298 (-8085 3825);
PAINT RED (-8085 3825);
FORCEPROP 1 LAST TOLERANCE 5%
J 0
(-8080 3925);
DISPLAY 0.638298 (-8080 3925);
FORCEPROP 1 LAST PACK_TYPE 0402LF
J 0
(-8085 3725);
DISPLAY 0.638298 (-8085 3725);
FORCEPROP 1 LAST WATTAGE 1/16W
J 0
(-8085 3875);
DISPLAY 0.638298 (-8085 3875);
FORCEPROP 2 LAST CDS_LIB pure_quanta
J 0
(-8125 3900);
DISPLAY INVISIBLE (-8125 3900);
FORCEPROP 1 LAST PATH I89
J 0
(-8075 4075);
DISPLAY 0.978723 (-8075 4075);
PAINT WHITE (-8075 4075);
DISPLAY INVISIBLE (-8075 4075);
FORCEPROP 1 LAST PART_NUMBER CS00002JB13
J 0
(-8085 3775);
DISPLAY 0.638298 (-8085 3775);
DISPLAY INVISIBLE (-8085 3775);
FORCEADD Q_CAP..1
(-6525 2900);
FORCEPROP 1 LAST LOCATION C206
J 0
(-6475 3000);
DISPLAY 0.978723 (-6475 3000);
PAINT WHITE (-6475 3000);
FORCEPROP 0 LAST $SEC 1
J 0
(-6475 3050);
DISPLAY 0.680851 (-6475 3050);
PAINT MONO (-6475 3050);
DISPLAY INVISIBLE (-6475 3050);
FORCEPROP 0 LAST CDS_SEC 1
J 0
(-6475 3050);
DISPLAY 0.680851 (-6475 3050);
DISPLAY INVISIBLE (-6475 3050);
FORCEPROP 1 LASTPIN (-6525 3000) $PN 1
J 0
(-6515 2980);
DISPLAY 0.787234 (-6515 2980);
PAINT MONO (-6515 2980);
FORCEPROP 1 LASTPIN (-6525 2800) $PN 2
J 0
(-6515 2780);
DISPLAY 0.787234 (-6515 2780);
PAINT MONO (-6515 2780);
FORCEPROP 1 LAST PACK_TYPE C0201
J 0
(-6475 2750);
DISPLAY 0.638298 (-6475 2750);
FORCEPROP 1 LAST MATERIAL X7S
J 0
(-6475 2800);
DISPLAY 0.638298 (-6475 2800);
FORCEPROP 1 LAST VOLTAGE 10V
J 0
(-6475 2900);
DISPLAY 0.638298 (-6475 2900);
FORCEPROP 1 LAST VALUE 0.1UF
J 0
(-6475 2950);
DISPLAY 0.638298 (-6475 2950);
FORCEPROP 1 LAST TOLERANCE 10%
J 0
(-6475 2850);
DISPLAY 0.638298 (-6475 2850);
FORCEPROP 2 LAST CDS_LIB pure_quanta
J 0
(-6525 2900);
DISPLAY INVISIBLE (-6525 2900);
FORCEPROP 1 LAST PATH I9
J 0
(-6475 3050);
DISPLAY 0.978723 (-6475 3050);
PAINT WHITE (-6475 3050);
DISPLAY INVISIBLE (-6475 3050);
FORCEPROP 1 LAST PART_NUMBER CH4102K6E00
J 0
(-6475 2750);
DISPLAY 0.978723 (-6475 2750);
DISPLAY INVISIBLE (-6475 2750);
FORCEADD Q_CAP..1
(-3050 950);
FORCEPROP 1 LAST LOCATION C306
J 0
(-3000 1050);
DISPLAY 0.978723 (-3000 1050);
PAINT WHITE (-3000 1050);
FORCEPROP 0 LAST $SEC 1
J 0
(-3000 1100);
DISPLAY 0.680851 (-3000 1100);
PAINT MONO (-3000 1100);
DISPLAY INVISIBLE (-3000 1100);
FORCEPROP 0 LAST CDS_SEC 1
J 0
(-3000 1100);
DISPLAY 0.680851 (-3000 1100);
DISPLAY INVISIBLE (-3000 1100);
FORCEPROP 1 LASTPIN (-3050 1050) $PN 1
J 0
(-3040 1030);
DISPLAY 0.787234 (-3040 1030);
PAINT MONO (-3040 1030);
FORCEPROP 1 LASTPIN (-3050 850) $PN 2
J 0
(-3040 830);
DISPLAY 0.787234 (-3040 830);
PAINT MONO (-3040 830);
FORCEPROP 1 LAST PACK_TYPE 0201
J 0
(-3000 800);
DISPLAY 0.510638 (-3000 800);
FORCEPROP 1 LAST MATERIAL X6S
J 0
(-3000 850);
DISPLAY 0.510638 (-3000 850);
FORCEPROP 1 LAST TOLERANCE 20%
J 0
(-3000 900);
DISPLAY 0.510638 (-3000 900);
FORCEPROP 1 LAST VALUE 1UF
J 0
(-3000 1000);
DISPLAY 0.510638 (-3000 1000);
FORCEPROP 1 LAST VOLTAGE 4V
J 0
(-3000 950);
DISPLAY 0.510638 (-3000 950);
FORCEPROP 2 LAST CDS_LIB pure_quanta
J 0
(-3050 950);
DISPLAY INVISIBLE (-3050 950);
FORCEPROP 1 LAST PATH I90
J 0
(-3000 1100);
DISPLAY 0.978723 (-3000 1100);
PAINT WHITE (-3000 1100);
DISPLAY INVISIBLE (-3000 1100);
FORCEPROP 1 LAST PART_NUMBER CH-10KMEE00
J 0
(-3000 800);
DISPLAY 0.510638 (-3000 800);
DISPLAY INVISIBLE (-3000 800);
FORCEADD Q_CAP..1
(-2500 950);
FORCEPROP 1 LAST LOCATION C315
J 0
(-2450 1050);
DISPLAY 0.978723 (-2450 1050);
PAINT WHITE (-2450 1050);
FORCEPROP 0 LAST $SEC 1
J 0
(-2450 1100);
DISPLAY 0.680851 (-2450 1100);
PAINT MONO (-2450 1100);
DISPLAY INVISIBLE (-2450 1100);
FORCEPROP 0 LAST CDS_SEC 1
J 0
(-2450 1100);
DISPLAY 0.680851 (-2450 1100);
DISPLAY INVISIBLE (-2450 1100);
FORCEPROP 1 LASTPIN (-2500 1050) $PN 1
J 0
(-2490 1030);
DISPLAY 0.787234 (-2490 1030);
PAINT MONO (-2490 1030);
FORCEPROP 1 LASTPIN (-2500 850) $PN 2
J 0
(-2490 830);
DISPLAY 0.787234 (-2490 830);
PAINT MONO (-2490 830);
FORCEPROP 1 LAST VALUE 1UF
J 0
(-2450 1000);
DISPLAY 0.510638 (-2450 1000);
FORCEPROP 1 LAST VOLTAGE 4V
J 0
(-2450 950);
DISPLAY 0.510638 (-2450 950);
FORCEPROP 1 LAST TOLERANCE 20%
J 0
(-2450 900);
DISPLAY 0.510638 (-2450 900);
FORCEPROP 1 LAST MATERIAL X6S
J 0
(-2450 850);
DISPLAY 0.510638 (-2450 850);
FORCEPROP 1 LAST PACK_TYPE 0201
J 0
(-2450 800);
DISPLAY 0.510638 (-2450 800);
FORCEPROP 2 LAST CDS_LIB pure_quanta
J 0
(-2500 950);
DISPLAY INVISIBLE (-2500 950);
FORCEPROP 1 LAST PATH I91
J 0
(-2450 1100);
DISPLAY 0.978723 (-2450 1100);
PAINT WHITE (-2450 1100);
DISPLAY INVISIBLE (-2450 1100);
FORCEPROP 1 LAST PART_NUMBER CH-10KMEE00
J 0
(-2450 800);
DISPLAY 0.510638 (-2450 800);
DISPLAY INVISIBLE (-2450 800);
FORCEADD Q_CAP..1
(-1825 2750);
FORCEPROP 1 LAST LOCATION C341
J 0
(-1775 2850);
DISPLAY 0.978723 (-1775 2850);
PAINT WHITE (-1775 2850);
FORCEPROP 0 LAST $SEC 1
J 0
(-1775 2900);
DISPLAY 0.680851 (-1775 2900);
PAINT MONO (-1775 2900);
DISPLAY INVISIBLE (-1775 2900);
FORCEPROP 0 LAST CDS_SEC 1
J 0
(-1775 2900);
DISPLAY 0.680851 (-1775 2900);
DISPLAY INVISIBLE (-1775 2900);
FORCEPROP 1 LASTPIN (-1825 2850) $PN 1
J 0
(-1815 2830);
DISPLAY 0.787234 (-1815 2830);
PAINT MONO (-1815 2830);
FORCEPROP 1 LASTPIN (-1825 2650) $PN 2
J 0
(-1815 2630);
DISPLAY 0.787234 (-1815 2630);
PAINT MONO (-1815 2630);
FORCEPROP 1 LAST VALUE 0.1UF
J 0
(-1775 2800);
DISPLAY 0.638298 (-1775 2800);
FORCEPROP 1 LAST MATERIAL X7S
J 0
(-1775 2650);
DISPLAY 0.638298 (-1775 2650);
FORCEPROP 1 LAST TOLERANCE 10%
J 0
(-1775 2700);
DISPLAY 0.638298 (-1775 2700);
FORCEPROP 1 LAST VOLTAGE 10V
J 0
(-1775 2750);
DISPLAY 0.638298 (-1775 2750);
FORCEPROP 1 LAST PACK_TYPE C0201
J 0
(-1775 2600);
DISPLAY 0.638298 (-1775 2600);
FORCEPROP 2 LAST CDS_LIB pure_quanta
J 0
(-1825 2750);
DISPLAY INVISIBLE (-1825 2750);
FORCEPROP 1 LAST PATH I92
J 0
(-1775 2900);
DISPLAY 0.978723 (-1775 2900);
PAINT WHITE (-1775 2900);
DISPLAY INVISIBLE (-1775 2900);
FORCEPROP 1 LAST PART_NUMBER CH4102K6E00
J 0
(-1775 2600);
DISPLAY 0.978723 (-1775 2600);
DISPLAY INVISIBLE (-1775 2600);
FORCEADD Q_CAP..1
(-1550 2750);
FORCEPROP 1 LAST LOCATION C350
J 0
(-1500 2850);
DISPLAY 0.978723 (-1500 2850);
PAINT WHITE (-1500 2850);
FORCEPROP 0 LAST $SEC 1
J 0
(-1500 2900);
DISPLAY 0.680851 (-1500 2900);
PAINT MONO (-1500 2900);
DISPLAY INVISIBLE (-1500 2900);
FORCEPROP 0 LAST CDS_SEC 1
J 0
(-1500 2900);
DISPLAY 0.680851 (-1500 2900);
DISPLAY INVISIBLE (-1500 2900);
FORCEPROP 1 LASTPIN (-1550 2850) $PN 1
J 0
(-1540 2830);
DISPLAY 0.787234 (-1540 2830);
PAINT MONO (-1540 2830);
FORCEPROP 1 LASTPIN (-1550 2650) $PN 2
J 0
(-1540 2630);
DISPLAY 0.787234 (-1540 2630);
PAINT MONO (-1540 2630);
FORCEPROP 1 LAST TOLERANCE 10%
J 0
(-1500 2700);
DISPLAY 0.638298 (-1500 2700);
FORCEPROP 1 LAST PACK_TYPE C0201
J 0
(-1500 2600);
DISPLAY 0.638298 (-1500 2600);
FORCEPROP 1 LAST MATERIAL X7S
J 0
(-1500 2650);
DISPLAY 0.638298 (-1500 2650);
FORCEPROP 1 LAST VOLTAGE 10V
J 0
(-1500 2750);
DISPLAY 0.638298 (-1500 2750);
FORCEPROP 1 LAST VALUE 0.1UF
J 0
(-1500 2800);
DISPLAY 0.638298 (-1500 2800);
FORCEPROP 2 LAST CDS_LIB pure_quanta
J 0
(-1550 2750);
DISPLAY INVISIBLE (-1550 2750);
FORCEPROP 1 LAST PATH I93
J 0
(-1500 2900);
DISPLAY 0.978723 (-1500 2900);
PAINT WHITE (-1500 2900);
DISPLAY INVISIBLE (-1500 2900);
FORCEPROP 1 LAST PART_NUMBER CH4102K6E00
J 0
(-1500 2600);
DISPLAY 0.978723 (-1500 2600);
DISPLAY INVISIBLE (-1500 2600);
FORCEADD Q_CAPP..1
(-1100 2050);
FORCEPROP 1 LAST LOCATION C7023
J 0
(-1050 2150);
DISPLAY 0.787234 (-1050 2150);
FORCEPROP 0 LAST $SEC 1
J 0
(-1050 2200);
DISPLAY 0.680851 (-1050 2200);
PAINT MONO (-1050 2200);
DISPLAY INVISIBLE (-1050 2200);
FORCEPROP 0 LAST CDS_SEC 1
J 0
(-1050 2200);
DISPLAY 0.680851 (-1050 2200);
DISPLAY INVISIBLE (-1050 2200);
FORCEPROP 1 LASTPIN (-1100 2150) $PN 1
J 0
(-1090 2135);
DISPLAY 0.787234 (-1090 2135);
PAINT MONO (-1090 2135);
FORCEPROP 1 LASTPIN (-1100 1950) $PN 2
J 0
(-1090 1935);
DISPLAY 0.787234 (-1090 1935);
PAINT MONO (-1090 1935);
FORCEPROP 1 LAST TOLERANCE 20%
J 0
(-1050 2050);
DISPLAY 0.510638 (-1050 2050);
FORCEPROP 1 LAST PACK_TYPE SMLF
J 0
(-1050 1900);
DISPLAY 0.510638 (-1050 1900);
FORCEPROP 1 LAST MATERIAL SPCAP
J 0
(-1050 1950);
DISPLAY 0.510638 (-1050 1950);
FORCEPROP 1 LAST VALUE 470UF
J 0
(-1050 2100);
DISPLAY 0.510638 (-1050 2100);
FORCEPROP 1 LAST VOLTAGE 2.5V
J 0
(-1050 2000);
DISPLAY 0.510638 (-1050 2000);
FORCEPROP 2 LAST CDS_LIB pure_quanta
J 0
(-1100 2050);
DISPLAY INVISIBLE (-1100 2050);
FORCEPROP 1 LAST PATH I94
J 0
(-1050 2200);
DISPLAY 0.978723 (-1050 2200);
DISPLAY INVISIBLE (-1050 2200);
FORCEPROP 1 LAST PART_NUMBER CH747LM8818
J 0
(-1050 1850);
DISPLAY 0.404255 (-1050 1850);
DISPLAY INVISIBLE (-1050 1850);
FORCEADD Q_CAPP..1
(-800 2050);
FORCEPROP 1 LAST LOCATION C7024
J 0
(-750 2150);
DISPLAY 0.787234 (-750 2150);
FORCEPROP 0 LAST $SEC 1
J 0
(-750 2200);
DISPLAY 0.680851 (-750 2200);
PAINT MONO (-750 2200);
DISPLAY INVISIBLE (-750 2200);
FORCEPROP 0 LAST CDS_SEC 1
J 0
(-750 2200);
DISPLAY 0.680851 (-750 2200);
DISPLAY INVISIBLE (-750 2200);
FORCEPROP 1 LASTPIN (-800 2150) $PN 1
J 0
(-790 2135);
DISPLAY 0.787234 (-790 2135);
PAINT MONO (-790 2135);
FORCEPROP 1 LASTPIN (-800 1950) $PN 2
J 0
(-790 1935);
DISPLAY 0.787234 (-790 1935);
PAINT MONO (-790 1935);
FORCEPROP 1 LAST MATERIAL SPCAP
J 0
(-750 1950);
DISPLAY 0.510638 (-750 1950);
FORCEPROP 1 LAST PACK_TYPE SMLF
J 0
(-750 1900);
DISPLAY 0.510638 (-750 1900);
FORCEPROP 1 LAST VALUE 470UF
J 0
(-750 2100);
DISPLAY 0.510638 (-750 2100);
FORCEPROP 1 LAST TOLERANCE 20%
J 0
(-750 2050);
DISPLAY 0.510638 (-750 2050);
FORCEPROP 1 LAST VOLTAGE 2.5V
J 0
(-750 2000);
DISPLAY 0.510638 (-750 2000);
FORCEPROP 2 LAST CDS_LIB pure_quanta
J 0
(-800 2050);
DISPLAY INVISIBLE (-800 2050);
FORCEPROP 1 LAST PATH I95
J 0
(-750 2200);
DISPLAY 0.978723 (-750 2200);
DISPLAY INVISIBLE (-750 2200);
FORCEPROP 1 LAST PART_NUMBER CH747LM8818
J 0
(-750 1850);
DISPLAY 0.404255 (-750 1850);
DISPLAY INVISIBLE (-750 1850);
FORCEADD Q_CAP..1
(-500 2050);
FORCEPROP 1 LAST LOCATION C7025
J 0
(-450 2150);
DISPLAY 0.638298 (-450 2150);
FORCEPROP 0 LAST $SEC 1
J 0
(-450 2200);
DISPLAY 0.680851 (-450 2200);
PAINT MONO (-450 2200);
DISPLAY INVISIBLE (-450 2200);
FORCEPROP 0 LAST CDS_SEC 1
J 0
(-450 2200);
DISPLAY 0.680851 (-450 2200);
DISPLAY INVISIBLE (-450 2200);
FORCEPROP 1 LASTPIN (-500 2150) $PN 1
J 0
(-490 2130);
DISPLAY 0.787234 (-490 2130);
PAINT MONO (-490 2130);
FORCEPROP 1 LASTPIN (-500 1950) $PN 2
J 0
(-490 1930);
DISPLAY 0.787234 (-490 1930);
PAINT MONO (-490 1930);
FORCEPROP 1 LAST PACK_TYPE C0805
J 0
(-450 1850);
DISPLAY 0.638298 (-450 1850);
FORCEPROP 1 LAST MATERIAL X6S
J 0
(-450 1950);
DISPLAY 0.638298 (-450 1950);
FORCEPROP 1 LAST TOLERANCE 20%
J 0
(-450 2000);
DISPLAY 0.638298 (-450 2000);
FORCEPROP 1 LAST VALUE 100UF
J 0
(-450 2100);
DISPLAY 0.638298 (-450 2100);
FORCEPROP 1 LAST VOLTAGE 4V
J 0
(-450 2050);
DISPLAY 0.638298 (-450 2050);
FORCEPROP 2 LAST CDS_LIB pure_quanta
J 0
(-500 2050);
DISPLAY INVISIBLE (-500 2050);
FORCEPROP 1 LAST PATH I96
J 0
(-450 2200);
DISPLAY 0.978723 (-450 2200);
PAINT WHITE (-450 2200);
DISPLAY INVISIBLE (-450 2200);
FORCEPROP 1 LAST PART_NUMBER CH710KMEA01
J 0
(-450 1900);
DISPLAY 0.638298 (-450 1900);
DISPLAY INVISIBLE (-450 1900);
FORCEADD DNS..2
(-8050 3875);
PAINT RED (-8050 3875);
FORCEPROP 2 LAST CDS_LIB mstr_misc
J 0
(-8050 3875);
DISPLAY INVISIBLE (-8050 3875);
FORCEPROP 1 LAST COMMENT_BODY TRUE
J 0
(-8050 3875);
DISPLAY INVISIBLE (-8050 3875);
FORCEADD DNS..2
(-7700 3525);
PAINT RED (-7700 3525);
FORCEPROP 2 LAST CDS_LIB mstr_misc
J 0
(-7700 3525);
DISPLAY INVISIBLE (-7700 3525);
FORCEPROP 1 LAST COMMENT_BODY TRUE
J 0
(-7700 3525);
DISPLAY INVISIBLE (-7700 3525);
FORCEADD CAD_NOTE..1
(-8175 2750);
FORCEPROP 0 LAST S1 L31/R704 COLAY WITH R653/R664
J 0
(-8300 2625);
DISPLAY 0.808511 (-8300 2625);
PAINT WHITE (-8300 2625);
FORCEPROP 2 LAST CDS_LIB pure_quanta_power
J 0
(-8175 2750);
DISPLAY INVISIBLE (-8175 2750);
FORCEPROP 1 LAST COMMENT_BODY TRUE
J 0
(-8150 2850);
DISPLAY 0.978723 (-8150 2850);
DISPLAY INVISIBLE (-8150 2850);
FORCEADD DNS..2
(-7700 3350);
PAINT RED (-7700 3350);
FORCEPROP 2 LAST CDS_LIB mstr_misc
J 0
(-7700 3350);
DISPLAY INVISIBLE (-7700 3350);
FORCEPROP 1 LAST COMMENT_BODY TRUE
J 0
(-7700 3350);
DISPLAY INVISIBLE (-7700 3350);
FORCEADD CAD_NOTE..1
(-5125 2250);
FORCEPROP 0 LAST S1 R705 AND R712 COLAY
J 0
(-5250 2125);
DISPLAY 0.808511 (-5250 2125);
PAINT WHITE (-5250 2125);
FORCEPROP 2 LAST CDS_LIB pure_quanta_power
J 0
(-5125 2250);
DISPLAY INVISIBLE (-5125 2250);
FORCEPROP 1 LAST COMMENT_BODY TRUE
J 0
(-5100 2350);
DISPLAY 0.978723 (-5100 2350);
DISPLAY INVISIBLE (-5100 2350);
FORCEADD DNS..2
(-4375 2550);
PAINT RED (-4375 2550);
FORCEPROP 2 LAST CDS_LIB mstr_misc
J 0
(-4375 2550);
DISPLAY INVISIBLE (-4375 2550);
FORCEPROP 1 LAST COMMENT_BODY TRUE
J 0
(-4375 2550);
DISPLAY INVISIBLE (-4375 2550);
FORCEADD QUANTA_TITLE_BLOCK_C..1
(0 0);
FORCEPROP 0 LAST CDS_CON_LAST_MODIFIED Thu Sep 14 16:13:04 2023
J 0
(-1885 15);
DISPLAY INVISIBLE (-1885 15);
FORCEPROP 1 LAST CUSTOM_TXT_CDS <CON_LAST_MODIFIED>
J 0
(-1885 15);
DISPLAY 0.978723 (-1885 15);
FORCEPROP 2 LAST CUSTOM_TXT_CDS <XR_PAGE_TITLE>
J 0
(-7890 5250);
DISPLAY 0.638298 (-7890 5250);
PAINT PINK (-7890 5250);
DISPLAY INVISIBLE (-7890 5250);
FORCEPROP 1 LAST CUSTOM_TXT_CDS <NAME_2>
J 0
(-3175 50);
FORCEPROP 1 LAST CUSTOM_TXT_CDS <NAME_1>
J 0
(-3175 175);
FORCEPROP 1 LAST CUSTOM_TXT_CDS <Q_NUMBER>
J 0
(-1403 103);
DISPLAY 1.212766 (-1403 103);
FORCEPROP 1 LAST CUSTOM_TXT_CDS <Q_PROJ>
J 0
(-2382 102);
DISPLAY 1.212766 (-2382 102);
FORCEPROP 1 LAST CUSTOM_TXT_CDS <Q_REV>
J 0
(-184 103);
DISPLAY 1.212766 (-184 103);
FORCEPROP 1 LAST CUSTOM_TXT_CDS <CON_PAGE_NUM> OF <CON_TOTAL_PAGES>
J 0
(-446 18);
DISPLAY 0.978723 (-446 18);
FORCEPROP 1 LAST Q_TITLE RETIMER_CPU1_P1 DECAPS(8)
J 0
(-9366 26);
DISPLAY 2.446809 (-9366 26);
PAINT GREEN (-9366 26);
FORCEPROP 2 LAST CDS_LIB pure_quanta
J 0
(0 0);
DISPLAY INVISIBLE (0 0);
FORCEPROP 1 LAST CDS_LMAN_SYM_OUTLINE -9475,6775,100,-125
J 0
(0 0);
DISPLAY 0.468085 (0 0);
PAINT GREEN (0 0);
DISPLAY INVISIBLE (0 0);
FORCEPROP 2 LAST PAGE_BORDER TRUE
J 0
(-7890 5250);
DISPLAY 0.638298 (-7890 5250);
PAINT PINK (-7890 5250);
DISPLAY INVISIBLE (-7890 5250);
FORCEPROP 2 LAST CDS_XR_PAGE_TITLE CR-335 : @T6G_MB_LIB.T6G(SCH_1):PAGE335
J 0
(-7890 5250);
DISPLAY 0.638298 (-7890 5250);
PAINT PINK (-7890 5250);
DISPLAY INVISIBLE (-7890 5250);
FORCEPROP 1 LAST Q_DEPT BU9
J 1
(-3763 49);
DISPLAY 1.957447 (-3763 49);
PAINT GREEN (-3763 49);
DISPLAY INVISIBLE (-3763 49);
FORCEPROP 1 LAST COMMENT_BODY TRUE
J 0
(12 -13);
DISPLAY 0.978723 (12 -13);
PAINT GREEN (12 -13);
DISPLAY INVISIBLE (12 -13);
WIRE 16 -1 (-500 2300)(-500 2150);
WIRE 16 -1 (-800 2300)(-500 2300);
WIRE 16 -1 (-800 2150)(-800 2300);
WIRE 16 -1 (-1100 2300)(-800 2300);
WIRE 16 -1 (-1100 2150)(-1100 2300);
WIRE 16 -1 (-1400 2300)(-1100 2300);
WIRE 16 -1 (-1400 2150)(-1400 2300);
WIRE 16 -1 (-1400 2300)(-1650 2300);
WIRE 16 -1 (-1650 2150)(-1650 2300);
WIRE 16 -1 (-1925 2300)(-1650 2300);
WIRE 16 -1 (-1925 2150)(-1925 2300);
WIRE 16 -1 (-2200 2300)(-1925 2300);
WIRE 16 -1 (-2200 2150)(-2200 2300);
WIRE 16 -1 (-2450 2300)(-2200 2300);
WIRE 16 -1 (-2450 2150)(-2450 2300);
WIRE 16 -1 (-2700 2300)(-2450 2300);
WIRE 16 -1 (-2700 2300)(-2700 2150);
WIRE 16 -1 (-2925 2300)(-2700 2300);
WIRE 16 -1 (-2925 2300)(-2925 2150);
WIRE 16 -1 (-3225 2300)(-2925 2300);
WIRE 16 -1 (-3225 2300)(-3225 2150);
WIRE 16 -1 (-3675 2300)(-3225 2300);
WIRE 16 -1 (-3675 2975)(-3675 2300);
WIRE 16 -1 (-3675 2300)(-3850 2300);
WIRE 16 -1 (-3675 3600)(-3675 2975);
WIRE 16 -1 (-3675 2975)(-3500 2975);
WIRE 16 -1 (-3500 2975)(-3275 2975);
WIRE 16 -1 (-3500 2975)(-3500 2850);
WIRE 16 -1 (-3675 4250)(-3675 3600);
WIRE 16 -1 (-3675 3600)(-3500 3600);
WIRE 16 -1 (-3500 3600)(-3275 3600);
WIRE 16 -1 (-3500 3475)(-3500 3600);
WIRE 16 -1 (-3675 4250)(-3500 4250);
WIRE 16 -1 (-3750 4250)(-3675 4250);
WIRE 16 -1 (-3275 2975)(-3025 2975);
WIRE 16 -1 (-3275 2975)(-3275 2850);
WIRE 16 -1 (-3025 2975)(-2800 2975);
WIRE 16 -1 (-3025 2975)(-3025 2850);
WIRE 16 -1 (-3500 4250)(-3275 4250);
WIRE 16 -1 (-3500 4250)(-3500 4100);
WIRE 16 -1 (-3500 4600)(-3500 4250);
WIRE 16 -1 (-3275 3600)(-3050 3600);
WIRE 16 -1 (-3275 3475)(-3275 3600);
WIRE 16 -1 (-3050 3600)(-2825 3600);
WIRE 16 -1 (-3050 3475)(-3050 3600);
WIRE 16 -1 (-3050 4250)(-3275 4250);
WIRE 16 -1 (-3275 4250)(-3275 4100);
WIRE 16 -1 (-2800 2975)(-2550 2975);
WIRE 16 -1 (-2800 2975)(-2800 2850);
WIRE 16 -1 (-2550 2975)(-2325 2975);
WIRE 16 -1 (-2550 2975)(-2550 2850);
WIRE 16 -1 (-2825 4250)(-3050 4250);
WIRE 16 -1 (-3050 4250)(-3050 4100);
WIRE 16 -1 (-2825 3600)(-2575 3600);
WIRE 16 -1 (-2825 3475)(-2825 3600);
WIRE 16 -1 (-2575 3600)(-2350 3600);
WIRE 16 -1 (-2575 3475)(-2575 3600);
WIRE 16 -1 (-2575 4250)(-2825 4250);
WIRE 16 -1 (-2825 4250)(-2825 4100);
WIRE 16 -1 (-2325 2975)(-2075 2975);
WIRE 16 -1 (-2325 2975)(-2325 2825);
WIRE 16 -1 (-1825 2975)(-2075 2975);
WIRE 16 -1 (-2075 2825)(-2075 2975);
WIRE 16 -1 (-2350 4250)(-2575 4250);
WIRE 16 -1 (-2575 4250)(-2575 4100);
WIRE 16 -1 (-2350 3600)(-2125 3600);
WIRE 16 -1 (-2350 3475)(-2350 3600);
WIRE 16 -1 (-2125 3600)(-1900 3600);
WIRE 16 -1 (-2125 3475)(-2125 3600);
WIRE 16 -1 (-2125 4250)(-2350 4250);
WIRE 16 -1 (-2350 4250)(-2350 4100);
WIRE 16 -1 (-1825 2975)(-1550 2975);
WIRE 16 -1 (-1825 2975)(-1825 2850);
WIRE 16 -1 (-1550 2975)(-1550 2850);
WIRE 16 -1 (-1900 4250)(-2125 4250);
WIRE 16 -1 (-2125 4250)(-2125 4100);
WIRE 16 -1 (-1900 3600)(-1675 3600);
WIRE 16 -1 (-1900 3475)(-1900 3600);
WIRE 16 -1 (-1425 3600)(-1675 3600);
WIRE 16 -1 (-1675 3475)(-1675 3600);
WIRE 16 -1 (-1600 4250)(-1900 4250);
WIRE 16 -1 (-1900 4250)(-1900 4100);
WIRE 16 -1 (-1600 4250)(-1300 4250);
WIRE 16 -1 (-1600 4250)(-1600 4100);
WIRE 16 -1 (-1425 3600)(-1425 3475);
WIRE 16 -1 (-1300 4250)(-1300 4100);
WIRE 16 -1 (-3500 3275)(-3500 3150);
WIRE 16 -1 (-3500 3150)(-3275 3150);
WIRE 16 -1 (-3275 3150)(-3050 3150);
WIRE 16 -1 (-3275 3275)(-3275 3150);
WIRE 16 -1 (-3050 3150)(-2825 3150);
WIRE 16 -1 (-3050 3275)(-3050 3150);
WIRE 16 -1 (-2825 3150)(-2575 3150);
WIRE 16 -1 (-2825 3275)(-2825 3150);
WIRE 16 -1 (-2575 3150)(-2350 3150);
WIRE 16 -1 (-2575 3275)(-2575 3150);
WIRE 16 -1 (-2350 3150)(-2125 3150);
WIRE 16 -1 (-2350 3275)(-2350 3150);
WIRE 16 -1 (-2125 3150)(-1900 3150);
WIRE 16 -1 (-2125 3275)(-2125 3150);
WIRE 16 -1 (-1900 3150)(-1675 3150);
WIRE 16 -1 (-1900 3275)(-1900 3150);
WIRE 16 -1 (-1425 3150)(-1675 3150);
WIRE 16 -1 (-1675 3275)(-1675 3150);
WIRE 16 -1 (-900 3150)(-1425 3150);
WIRE 16 -1 (-1425 3275)(-1425 3150);
WIRE 16 -1 (-900 3750)(-900 3150);
WIRE 16 -1 (-900 3150)(-900 2425);
WIRE 16 -1 (-900 2425)(-1550 2425);
WIRE 16 -1 (-900 2425)(-900 2375);
WIRE 16 -1 (-900 3750)(-1300 3750);
WIRE 16 -1 (-1300 3900)(-1300 3750);
WIRE 16 -1 (-1300 3750)(-1600 3750);
WIRE 16 -1 (-1825 2425)(-1550 2425);
WIRE 16 -1 (-1550 2650)(-1550 2425);
WIRE 16 -1 (-1825 2650)(-1825 2425);
WIRE 16 -1 (-1825 2425)(-2075 2425);
WIRE 16 -1 (-1600 3900)(-1600 3750);
WIRE 16 -1 (-1600 3750)(-1900 3750);
WIRE 16 -1 (-1900 3900)(-1900 3750);
WIRE 16 -1 (-1900 3750)(-2125 3750);
WIRE 16 -1 (-2075 2625)(-2075 2425);
WIRE 16 -1 (-2075 2425)(-2325 2425);
WIRE 16 -1 (-2325 2625)(-2325 2425);
WIRE 16 -1 (-2550 2425)(-2325 2425);
WIRE 16 -1 (-2125 3900)(-2125 3750);
WIRE 16 -1 (-2125 3750)(-2350 3750);
WIRE 16 -1 (-2350 3900)(-2350 3750);
WIRE 16 -1 (-2350 3750)(-2575 3750);
WIRE 16 -1 (-2550 2650)(-2550 2425);
WIRE 16 -1 (-2800 2425)(-2550 2425);
WIRE 16 -1 (-2800 2650)(-2800 2425);
WIRE 16 -1 (-3025 2425)(-2800 2425);
WIRE 16 -1 (-2575 3900)(-2575 3750);
WIRE 16 -1 (-2575 3750)(-2825 3750);
WIRE 16 -1 (-2825 3900)(-2825 3750);
WIRE 16 -1 (-3050 3750)(-2825 3750);
WIRE 16 -1 (-3025 2650)(-3025 2425);
WIRE 16 -1 (-3275 2425)(-3025 2425);
WIRE 16 -1 (-3275 2650)(-3275 2425);
WIRE 16 -1 (-3500 2425)(-3275 2425);
WIRE 16 -1 (-3050 3900)(-3050 3750);
WIRE 16 -1 (-3275 3750)(-3050 3750);
WIRE 16 -1 (-3275 3900)(-3275 3750);
WIRE 16 -1 (-3500 3750)(-3275 3750);
WIRE 16 -1 (-3500 2650)(-3500 2425);
WIRE 16 -1 (-3500 3900)(-3500 3750);
WIRE 16 -1 (-1150 5500)(-1150 5325);
WIRE 16 -1 (-1425 5500)(-1150 5500);
WIRE 16 -1 (-1425 5500)(-1425 5325);
WIRE 16 -1 (-1675 5500)(-1425 5500);
WIRE 16 -1 (-1675 5325)(-1675 5500);
WIRE 16 -1 (-1950 5500)(-1675 5500);
WIRE 16 -1 (-1950 5500)(-1950 5325);
WIRE 16 -1 (-2250 5500)(-1950 5500);
WIRE 16 -1 (-2250 5500)(-2250 5350);
WIRE 16 -1 (-2550 5500)(-2250 5500);
WIRE 16 -1 (-2550 5500)(-2550 5350);
WIRE 16 -1 (-2850 5500)(-2550 5500);
WIRE 16 -1 (-2850 5500)(-2850 5350);
WIRE 16 -1 (-3175 5500)(-2850 5500);
WIRE 16 -1 (-3175 5500)(-3175 5375);
WIRE 16 -1 (-3450 5500)(-3175 5500);
WIRE 16 -1 (-3450 5500)(-3450 5375);
WIRE 16 -1 (-4325 5500)(-3450 5500);
WIRE 16 -1 (-4325 5725)(-4325 5500);
WIRE 16 -1 (-4325 4250)(-4325 5500);
WIRE 16 -1 (-3950 4250)(-4325 4250);
WIRE 16 -1 (-4325 4250)(-4325 2675);
WIRE 16 -1 (-1150 5125)(-1150 4950);
WIRE 16 -1 (-1150 4950)(-1225 4950);
WIRE 16 -1 (-1225 4950)(-1425 4950);
WIRE 16 -1 (-1225 4950)(-1225 4875);
WIRE 16 -1 (-1425 5125)(-1425 4950);
WIRE 16 -1 (-1675 4950)(-1425 4950);
WIRE 16 -1 (-1675 5125)(-1675 4950);
WIRE 16 -1 (-1950 4950)(-1675 4950);
WIRE 16 -1 (-1950 5125)(-1950 4950);
WIRE 16 -1 (-1950 4950)(-2250 4950);
WIRE 16 -1 (-2250 5150)(-2250 4950);
WIRE 16 -1 (-2550 4950)(-2250 4950);
WIRE 16 -1 (-2550 5150)(-2550 4950);
WIRE 16 -1 (-2850 4950)(-2550 4950);
WIRE 16 -1 (-2850 5150)(-2850 4950);
WIRE 16 -1 (-3175 4950)(-2850 4950);
WIRE 16 -1 (-3175 5175)(-3175 4950);
WIRE 16 -1 (-3450 4950)(-3175 4950);
WIRE 16 -1 (-3450 5175)(-3450 4950);
WIRE 16 -1 (-8175 4100)(-8125 4100);
WIRE 16 -1 (-8175 4250)(-8175 4100);
WIRE 16 -1 (-8175 4100)(-8225 4100);
WIRE 16 -1 (-8125 4100)(-8125 4000);
WIRE 16 -1 (-8225 4100)(-8225 4025);
WIRE 16 -1 (-8175 4975)(-8175 4250);
WIRE 16 -1 (-8175 4250)(-7900 4250);
WIRE 16 -1 (-7075 4975)(-8175 4975);
WIRE 16 -1 (-8175 5050)(-8175 4975);
WIRE 16 -1 (-7075 4975)(-6825 4975);
WIRE 16 -1 (-7075 4975)(-7075 4925);
WIRE 16 -1 (-6825 4975)(-6575 4975);
WIRE 16 -1 (-6825 4975)(-6825 4925);
WIRE 16 -1 (-6575 4975)(-6325 4975);
WIRE 16 -1 (-6575 4975)(-6575 4900);
WIRE 16 -1 (-6325 4975)(-6325 4900);
WIRE 16 -1 (-6325 4700)(-6325 4575);
WIRE 16 -1 (-6400 4575)(-6325 4575);
WIRE 16 -1 (-6575 4575)(-6400 4575);
WIRE 16 -1 (-6575 4700)(-6575 4575);
WIRE 16 -1 (-6825 4575)(-6575 4575);
WIRE 16 -1 (-6825 4725)(-6825 4575);
WIRE 16 -1 (-7075 4575)(-6825 4575);
WIRE 16 -1 (-7075 4725)(-7075 4575);
WIRE 16 -1 (-5175 4250)(-5175 4100);
WIRE 16 -1 (-5175 4250)(-5450 4250);
WIRE 16 -1 (-5450 4250)(-5450 4100);
WIRE 16 -1 (-5450 4250)(-5700 4250);
WIRE 16 -1 (-5700 4250)(-5700 4100);
WIRE 16 -1 (-5700 4250)(-5950 4250);
WIRE 16 -1 (-5950 4250)(-5950 4100);
WIRE 16 -1 (-6175 4250)(-5950 4250);
WIRE 16 -1 (-6175 4250)(-6175 4100);
WIRE 16 -1 (-6175 4250)(-6375 4250);
WIRE 16 -1 (-6375 4250)(-6375 4100);
WIRE 16 -1 (-6375 4250)(-6600 4250);
WIRE 16 -1 (-6600 4250)(-6600 4100);
WIRE 16 -1 (-6800 4250)(-6600 4250);
WIRE 16 -1 (-6800 4250)(-6800 4100);
WIRE 16 -1 (-6800 4250)(-7000 4250);
WIRE 16 -1 (-7000 4250)(-7000 4100);
WIRE 16 -1 (-7225 4250)(-7000 4250);
WIRE 16 -1 (-7225 4250)(-7225 4100);
WIRE 16 -1 (-7225 4250)(-7325 4250);
WIRE 16 -1 (-7325 4425)(-7325 4250);
WIRE 16 -1 (-7325 4250)(-7700 4250);
WIRE 16 -1 (-7325 3475)(-7325 4250);
WIRE 16 -1 (-7425 3475)(-7325 3475);
WIRE 16 -1 (-7425 3475)(-7425 3375);
WIRE 16 -1 (-7425 3575)(-7425 3475);
WIRE 16 -1 (-7625 3575)(-7425 3575);
WIRE 16 -1 (-7625 3375)(-7425 3375);
WIRE 16 -1 (-5175 3900)(-5175 3800);
WIRE 16 -1 (-5450 3800)(-5175 3800);
WIRE 16 -1 (-5450 3900)(-5450 3800);
WIRE 16 -1 (-5700 3800)(-5450 3800);
WIRE 16 -1 (-5700 3900)(-5700 3800);
WIRE 16 -1 (-5950 3800)(-5700 3800);
WIRE 16 -1 (-5950 3900)(-5950 3800);
WIRE 16 -1 (-6175 3800)(-5950 3800);
WIRE 16 -1 (-6375 3800)(-6175 3800);
WIRE 16 -1 (-6175 3900)(-6175 3800);
WIRE 16 -1 (-6175 3800)(-6175 3725);
WIRE 16 -1 (-6375 3900)(-6375 3800);
WIRE 16 -1 (-6600 3800)(-6375 3800);
WIRE 16 -1 (-6600 3900)(-6600 3800);
WIRE 16 -1 (-6800 3800)(-6600 3800);
WIRE 16 -1 (-6800 3900)(-6800 3800);
WIRE 16 -1 (-7000 3800)(-6800 3800);
WIRE 16 -1 (-7000 3900)(-7000 3800);
WIRE 16 -1 (-7225 3800)(-7000 3800);
WIRE 16 -1 (-7225 3900)(-7225 3800);
WIRE 16 -1 (-6800 2825)(-6800 2650);
WIRE 16 -1 (-6800 2650)(-6525 2650);
WIRE 16 -1 (-6525 2800)(-6525 2650);
WIRE 16 -1 (-6525 2650)(-6525 2550);
WIRE 16 -1 (-3225 1950)(-3225 1825);
WIRE 16 -1 (-3225 1825)(-2925 1825);
WIRE 16 -1 (-2925 1825)(-2700 1825);
WIRE 16 -1 (-2925 1950)(-2925 1825);
WIRE 16 -1 (-2700 1825)(-2450 1825);
WIRE 16 -1 (-2700 1950)(-2700 1825);
WIRE 16 -1 (-2450 1825)(-2200 1825);
WIRE 16 -1 (-2450 1950)(-2450 1825);
WIRE 16 -1 (-2200 1825)(-1925 1825);
WIRE 16 -1 (-2200 1950)(-2200 1825);
WIRE 16 -1 (-1650 1825)(-1925 1825);
WIRE 16 -1 (-1925 1950)(-1925 1825);
WIRE 16 -1 (-1650 1825)(-1400 1825);
WIRE 16 -1 (-1650 1950)(-1650 1825);
WIRE 16 -1 (-1100 1825)(-1400 1825);
WIRE 16 -1 (-1400 1950)(-1400 1825);
WIRE 16 -1 (-1400 1825)(-1400 1675);
WIRE 16 -1 (-800 1825)(-1100 1825);
WIRE 16 -1 (-1100 1950)(-1100 1825);
WIRE 16 -1 (-500 1825)(-800 1825);
WIRE 16 -1 (-800 1950)(-800 1825);
WIRE 16 -1 (-500 1950)(-500 1825);
WIRE 16 -1 (-8075 3375)(-7825 3375);
WIRE 16 -1 (-8075 3475)(-8075 3375);
WIRE 16 -1 (-8075 3575)(-8075 3475);
WIRE 16 -1 (-8175 3475)(-8075 3475);
WIRE 16 -1 (-8175 3475)(-8175 3650);
WIRE 16 -1 (-8175 3150)(-8175 3475);
WIRE 16 -1 (-7825 3575)(-8075 3575);
WIRE 16 -1 (-8175 3150)(-6925 3150);
WIRE 16 -1 (-8175 3650)(-8125 3650);
WIRE 16 -1 (-8225 3650)(-8175 3650);
WIRE 16 -1 (-8225 3650)(-8225 3825);
WIRE 16 -1 (-8125 3650)(-8125 3800);
WIRE 16 -1 (-6800 3150)(-6925 3150);
WIRE 16 -1 (-6925 3150)(-6925 3250);
WIRE 16 -1 (-6800 3150)(-6525 3150);
WIRE 16 -1 (-6800 3025)(-6800 3150);
WIRE 16 -1 (-6525 3150)(-6525 3000);
WIRE 16 -1 (-3050 850)(-3050 725);
WIRE 16 -1 (-3050 725)(-2800 725);
WIRE 16 -1 (-2800 725)(-2500 725);
WIRE 16 -1 (-2800 850)(-2800 725);
WIRE 16 -1 (-2500 850)(-2500 725);
WIRE 16 -1 (-2500 725)(-2350 725);
WIRE 16 -1 (-2250 725)(-2350 725);
WIRE 16 -1 (-2350 725)(-2350 675);
WIRE 16 -1 (-2250 850)(-2250 725);
WIRE 16 -1 (-4325 2475)(-4325 2300);
WIRE 16 -1 (-4325 2300)(-4050 2300);
WIRE 16 -1 (-4325 1200)(-4325 2300);
WIRE 16 -1 (-4325 1200)(-3175 1200);
WIRE 16 -1 (-3050 1200)(-3175 1200);
WIRE 16 -1 (-3175 1425)(-3175 1200);
WIRE 16 -1 (-2800 1200)(-3050 1200);
WIRE 16 -1 (-3050 1200)(-3050 1050);
WIRE 16 -1 (-2500 1200)(-2800 1200);
WIRE 16 -1 (-2800 1200)(-2800 1050);
WIRE 16 -1 (-2250 1200)(-2500 1200);
WIRE 16 -1 (-2500 1050)(-2500 1200);
WIRE 16 -1 (-2250 1050)(-2250 1200);
DOT 1 (-1100 1825);
DOT 1 (-1100 2300);
DOT 1 (-800 1825);
DOT 1 (-800 2300);
DOT 1 (-1400 1825);
DOT 1 (-1400 2300);
DOT 1 (-1900 3150);
DOT 1 (-2575 3750);
DOT 1 (-3025 2425);
DOT 1 (-2800 2425);
DOT 1 (-8175 4250);
DOT 1 (-8175 4100);
DOT 1 (-7425 3475);
DOT 1 (-3275 2425);
DOT 1 (-3275 3150);
DOT 1 (-6600 3800);
DOT 1 (-8175 4975);
DOT 1 (-8075 3475);
DOT 1 (-8175 3650);
DOT 1 (-6525 2650);
DOT 1 (-7000 3800);
DOT 1 (-7325 4250);
DOT 1 (-7225 4250);
DOT 1 (-7000 4250);
DOT 1 (-7075 4975);
DOT 1 (-6800 4250);
DOT 1 (-6825 4575);
DOT 1 (-6375 3800);
DOT 1 (-6175 4250);
DOT 1 (-5700 3800);
DOT 1 (-5450 3800);
DOT 1 (-4325 4250);
DOT 1 (-4325 5500);
DOT 1 (-3175 1200);
DOT 1 (-2800 725);
DOT 1 (-2350 725);
DOT 1 (-2800 1200);
DOT 1 (-3675 2300);
DOT 1 (-2925 1825);
DOT 1 (-3225 2300);
DOT 1 (-2925 2300);
DOT 1 (-3675 2975);
DOT 1 (-3500 2975);
DOT 1 (-3675 3600);
DOT 1 (-3500 3600);
DOT 1 (-2825 3150);
DOT 1 (-2700 1825);
DOT 1 (-2450 1825);
DOT 1 (-2450 2300);
DOT 1 (-2550 2425);
DOT 1 (-2200 1825);
DOT 1 (-1925 1825);
DOT 1 (-2575 3150);
DOT 1 (-2125 3150);
DOT 1 (-2125 3600);
DOT 1 (-1650 1825);
DOT 1 (-900 2425);
DOT 1 (-1675 3600);
DOT 1 (-900 3150);
DOT 1 (-3675 4250);
DOT 1 (-3500 4250);
DOT 1 (-3275 3750);
DOT 1 (-2825 3750);
DOT 1 (-3050 3750);
DOT 1 (-2825 4250);
DOT 1 (-3050 4250);
DOT 1 (-3450 5500);
DOT 1 (-3175 4950);
DOT 1 (-3175 5500);
DOT 1 (-2850 5500);
DOT 1 (-1900 3750);
DOT 1 (-2550 5500);
DOT 1 (-2250 4950);
DOT 1 (-1950 4950);
DOT 1 (-1950 5500);
DOT 1 (-1600 3750);
DOT 1 (-1300 3750);
DOT 1 (-1600 4250);
DOT 1 (-1675 4950);
DOT 1 (-1425 4950);
DOT 1 (-1675 5500);
DOT 1 (-1425 5500);
DOT 1 (-1225 4950);
DOT 1 (-8175 3475);
DOT 1 (-4325 2300);
DOT 1 (-5450 4250);
DOT 1 (-6825 4975);
DOT 1 (-6575 4975);
DOT 1 (-6600 4250);
DOT 1 (-6925 3150);
DOT 1 (-6375 4250);
DOT 1 (-5700 4250);
DOT 1 (-5950 3800);
DOT 1 (-6175 3800);
DOT 1 (-6800 3150);
DOT 1 (-6800 3800);
DOT 1 (-6575 4575);
DOT 1 (-5950 4250);
DOT 1 (-2250 5500);
DOT 1 (-2850 4950);
DOT 1 (-2550 4950);
DOT 1 (-2350 4250);
DOT 1 (-2350 3750);
DOT 1 (-2575 3600);
DOT 1 (-1425 3150);
DOT 1 (-2700 2300);
DOT 1 (-2125 4250);
DOT 1 (-3275 4250);
DOT 1 (-2125 3750);
DOT 1 (-3275 3600);
DOT 1 (-1900 4250);
DOT 1 (-2575 4250);
DOT 1 (-2350 3600);
DOT 1 (-1900 3600);
DOT 1 (-3050 3600);
DOT 1 (-2350 3150);
DOT 1 (-2325 2425);
DOT 1 (-1675 3150);
DOT 1 (-3025 2975);
DOT 1 (-3275 2975);
DOT 1 (-1650 2300);
DOT 1 (-2550 2975);
DOT 1 (-3050 3150);
DOT 1 (-2200 2300);
DOT 1 (-1925 2300);
DOT 1 (-2325 2975);
DOT 1 (-2800 2975);
DOT 1 (-2075 2975);
DOT 1 (-2075 2425);
DOT 1 (-1825 2425);
DOT 1 (-1825 2975);
DOT 1 (-1550 2425);
DOT 1 (-2825 3600);
DOT 1 (-3050 1200);
DOT 1 (-2500 1200);
DOT 1 (-2500 725);
QUIT
